PARTS LIST

78.10421.2FL       C402H22                      C1
78.10521.2BL       C603H36                      C2
78.10521.2BL       C603H36                      C8
078.10521.08F1     C402-TO0D2H24                C9
078.10521.08F1     C402-TO0D2H24                C10
078.10521.08F1     C402-TO0D2H24                C11
078.10521.08F1     C402-TO0D2H24                C12
78.10521.2BL       C603H36                      C13
78.10224.2FL       C402H22                      C14
78.10521.2BL       C603H36                      C15
78.10521.2BL       C603H36                      C16
78.18034.1FL       C402H22                      C17
78.10521.2BL       C603H36                      C18
78.10521.2BL       C603H36                      C19
78.18034.1FL       C402H22                      C20
78.10521.2BL       C603H36                      C21
78.10521.2BL       C603H36                      C22
78.22522.21L       C805H54                      C25
78.10521.2BL       C603H36                      C26
78.10421.2FL       C402H22                      C27
78.22522.21L       C805H54                      C28
78.22522.21L       C805H54                      C29
78.10421.2FL       C402H22                      C30
78.10521.2BL       C603H36                      C31
78.10421.2FL       C402H22                      C32
78.10421.2FL       C402H22                      C33
78.10421.2FL       C402H22                      C34
078.10521.08F1     C402-TO0D2H24                C35
78.10421.2FL       C402H22                      C36
78.10421.2FL       C402H22                      C37
78.10421.2FL       C402H22                      C38
78.10421.2FL       C402H22                      C39
78.10421.2FL       C402H22                      C40
78.10421.2FL       C402H22                      C41
78.10421.2FL       C402H22                      C44
78.10421.2FL       C402H22                      C49
78.10421.2FL       C402H22                      C50
78.10421.2FL       C402H22                      C51
78.10421.2FL       C402H22                      C52
78.10322.2FL       C402H22                      C53
78.10521.2BL       C603H36                      C54
78.10421.2FL       C402H22                      C55
78.10521.2BL       C603H36                      C56
78.10620.21L       C805H58                      C57
78.10521.2BL       C603H36                      C58
78.10521.2BL       C603H36                      C59
78.10521.2BL       C603H36                      C60
78.10521.2BL       C603H36                      C61
78.10521.2BL       C603H36                      C62
078.47522.0211     C805H58                      C63
78.10521.2BL       C603H36                      C64
78.10521.2BL       C603H36                      C65
78.10421.2FL       C402H22                      C66
78.10421.2FL       C402H22                      C67
78.10421.2FL       C402H22                      C68
78.10421.2FL       C402H22                      C69
78.10421.2FL       C402H22                      C70
78.10421.2FL       C402H22                      C71
78.10421.2FL       C402H22                      C72
78.10421.2FL       C402H22                      C73
78.10421.2FL       C402H22                      C74
78.10421.2FL       C402H22                      C75
78.10322.2FL       C402H22                      C76
78.10421.2FL       C402H22                      C78
78.10421.2FL       C402H22                      C79
78.10421.2FL       C402H22                      C80
078.47522.0211     C805H58                      C81
78.33034.1FL       C402H22                      C82
78.10521.2BL       C603H36                      C83
78.10421.2FL       C402H22                      C84
78.10421.2FL       C402H22                      C85
78.10421.2FL       C402H22                      C86
78.10521.2BL       C603H36                      C87
78.10134.1FL       C402H22                      C88
078.47522.0211     C805H58                      C89
78.10521.2BL       C603H36                      C90
78.10134.1FL       C402H22                      C91
78.10521.2BL       C603H36                      C92
78.10421.2FL       C402H22                      C93
78.10134.1FL       C402H22                      C94
78.10521.2BL       C603H36                      C95
78.10134.1FL       C402H22                      C96
78.10521.2BL       C603H36                      C97
78.10521.2BL       C603H36                      C98
78.10521.2BL       C603H36                      C99
78.10521.2BL       C603H36                      C100
78.10521.2BL       C603H36                      C101
78.10521.2BL       C603H36                      C102
78.10421.2FL       C402H22                      C103
078.10620.08B1     C603H40                      C104
78.10134.1FL       C402H22                      C105
078.47522.0211     C805H58                      C106
78.10521.2BL       C603H36                      C107
78.10521.2BL       C603H36                      C108
78.10521.2BL       C603H36                      C109
78.10521.2BL       C603H36                      C110
78.10521.2BL       C603H36                      C113
78.10521.2BL       C603H36                      C114
078.10620.08B1     C603H40                      C115
078.47522.0211     C805H58                      C116
78.10422.2FL       C402H22                      C117
78.10422.2FL       C402H22                      C118
78.10422.2FL       C402H22                      C120
78.10422.2FL       C402H22                      C122
78.10422.2FL       C402H22                      C123
78.10422.2FL       C402H22                      C125
78.10421.2FL       C402H22                      C126
78.10421.2FL       C402H22                      C127
78.10522.2BL       C603H36                      C128
78.10224.2FL       C402H22                      C129
78.10421.2FL       C402H22                      C130
78.10322.2FL       C402H22                      C131
78.22621.82L       C1206H75                     C132
78.15322.2FL       C402H22                      C133
78.15322.2FL       C402H22                      C134
78.10421.2FL       C402H22                      C135
78.10421.2FL       C402H22                      C136
78.10421.2FL       C402H22                      C137
78.10422.2FL       C402H22                      C138
78.10424.2BL       C603H36                      C139
78.10421.2FL       C402H22                      C141
78.10521.2BL       C603H36                      C144
78.10521.2BL       C603H36                      C145
78.33324.2BL       C603H36                      C146
78.10521.2BL       C603H36                      C147
78.10424.2BL       C603H36                      C148
78.10424.2BL       C603H36                      C149
78.10424.2BL       C603H36                      C150
078.10621.0211     C805H58                      C151
078.10621.0211     C805H58                      C152
078.10621.0211     C805H58                      C153
078.10621.0211     C805H58                      C154
078.10621.0211     C805H58                      C155
78.10521.2BL       C603H36                      C156
078.47522.0211     C805H58                      C157
78.10424.2BL       C603H36                      C158
78.22224.2FL       C402H22                      C159
78.10424.2BL       C603H36                      C160
78.10521.2BL       C603H36                      C161
78.10224.2FL       C402H22                      C162
078.68034.C1F1     C402H22                      C163
078.10621.0211     C805H58                      C164
078.10621.0211     C805H58                      C165
078.10621.0211     C805H58                      C166
77.21071.02L       CT7343H79                    C167
77.21571.18L       CT7343H119                   C168
78.10421.2FL       C402H22                      C169
078.10621.0211     C805H58                      C170
078.10621.0211     C805H58                      C171
78.10620.21L       C805H58                      C172
078.10621.0211     C805H58                      C173
78.10620.21L       C805H58                      C174
077.51571.0001     CT7343H83                    C175
078.10621.0211     C805H58                      C176
078.10621.0211     C805H58                      C177
78.10424.2BL       C603H36                      C178
078.47522.0211     C805H58                      C179
78.22224.2FL       C402H22                      C180
78.10422.2FL       C402H22                      C181
78.10521.2BL       C603H36                      C182
78.10224.2FL       C402H22                      C183
078.68034.C1F1     C402H22                      C184
78.10421.2FL       C402H22                      C186
78.10620.21L       C805H58                      C187
78.10620.21L       C805H58                      C188
78.10422.2FL       C402H22                      C189
78.10224.2FL       C402H22                      C190
78.10620.21L       C805H58                      C191
78.10620.21L       C805H58                      C192
78.10620.21L       C805H58                      C193
78.10620.21L       C805H58                      C194
78.10421.2FL       C402H22                      C195
78.47124.2FL       C402H22                      C196
78.10521.2BL       C603H36                      C197
78.10421.2FL       C402H22                      C198
78.10620.21L       C805H58                      C199
78.10620.21L       C805H58                      C200
78.10421.2FL       C402H22                      C201
78.10521.2BL       C603H36                      C202
78.10421.2FL       C402H22                      C203
078.10621.0211     C805H58                      C204
078.10621.0211     C805H58                      C205
78.10134.1FL       C402H22                      C206
78.10424.2BL       C603H36                      C207
78.33224.2FL       C402H22                      C208
78.10521.2BL       C603H36                      C209
78.22224.2FL       C402H22                      C210
78.10424.2BL       C603H36                      C211
78.10224.2FL       C402H22                      C212
78.10521.2BL       C603H36                      C213
78.10421.2FL       C402H22                      C214
78.10620.21L       C805H58                      C215
78.10620.21L       C805H58                      C216
78.10620.21L       C805H58                      C217
78.10620.21L       C805H58                      C218
78.47422.2BL       C603H36                      C219
78.10224.2FL       C402H22                      C222
78.10620.21L       C805H58                      C223
78.10620.21L       C805H58                      C224
78.10620.21L       C805H58                      C225
78.10620.21L       C805H58                      C226
78.10421.2FL       C402H22                      C227
78.47124.2FL       C402H22                      C228
78.10521.2BL       C603H36                      C229
78.10421.2FL       C402H22                      C230
78.10620.21L       C805H58                      C231
78.10620.21L       C805H58                      C232
78.10421.2FL       C402H22                      C233
78.10224.2FL       C402H22                      C234
78.10620.21L       C805H58                      C235
78.10620.21L       C805H58                      C236
78.10620.21L       C805H58                      C237
78.10620.21L       C805H58                      C238
78.10421.2FL       C402H22                      C239
78.47124.2FL       C402H22                      C240
78.10521.2BL       C603H36                      C241
78.10421.2FL       C402H22                      C242
78.10620.21L       C805H58                      C243
78.10620.21L       C805H58                      C244
78.10421.2FL       C402H22                      C245
77.21571.18L       CT7343H119                   C246
78.10421.2FL       C402H22                      C485
78.10421.2FL       C402H22                      C502
78.10421.2FL       C402H22                      C503
78.10421.2FL       C402H22                      C504
78.10421.2FL       C402H22                      C505
78.10421.2FL       C402H22                      C506
78.10421.2FL       C402H22                      C507
78.10421.2FL       C402H22                      C508
078.10621.0211     C805H58                      C511
078.10621.0211     C805H58                      C512
78.10421.2FL       C402H22                      C513
78.10422.2FL       C402H22                      C518
78.10422.2FL       C402H22                      C519
78.10422.2FL       C402H22                      C520
78.10422.2FL       C402H22                      C522
078.10521.08F1     C402-TO0D2H24                C524
078.1022S.022L     C1206H58                     C525
078.1022S.022L     C1206H58                     C528
078.1022S.022L     C1206H58                     C529
78.10421.2FL       C402H22                      C601
78.10421.2FL       C402H22                      C602
78.10421.2FL       C402H22                      C605
78.10620.21L       C805H58                      C606
78.10421.2FL       C402H22                      C607
78.10421.2FL       C402H22                      C608
78.10421.2FL       C402H22                      C609
78.10620.21L       C805H58                      C610
78.10421.2FL       C402H22                      C612
78.10421.2FL       C402H22                      C613
78.10620.21L       C805H58                      C614
78.10421.2FL       C402H22                      C615
78.10421.2FL       C402H22                      C616
78.10620.21L       C805H58                      C617
78.10421.2FL       C402H22                      C618
78.10421.2FL       C402H22                      C619
78.10421.2FL       C402H22                      C620
78.10620.21L       C805H58                      C621
78.10421.2FL       C402H22                      C623
78.10421.2FL       C402H22                      C624
78.10620.21L       C805H58                      C625
78.10421.2FL       C402H22                      C626
78.10422.2FL       C402H22                      C627
78.10421.2FL       C402H22                      C628
78.10421.2FL       C402H22                      C629
78.10421.2FL       C402H22                      C630
78.10421.2FL       C402H22                      C631
78.10421.2FL       C402H22                      C632
78.10421.2FL       C402H22                      C633
78.10421.2FL       C402H22                      C634
078.10621.0211     C805H58                      C635
078.10621.0211     C805H58                      C636
078.10621.0211     C805H58                      C637
078.10621.0211     C805H58                      C638
78.10421.2FL       C402H22                      C639
78.10620.21L       C805H58                      C640
78.10421.2FL       C402H22                      C641
78.10620.21L       C805H58                      C643
78.47124.2FL       C402H22                      C644
78.10521.2BL       C603H36                      C645
78.22224.2FL       C402H22                      C646
078.47522.0211     C805H58                      C647
078.68034.C1F1     C402H22                      C648
78.10620.21L       C805H58                      C650
78.10424.2BL       C603H36                      C652
78.10421.2FL       C402H22                      C653
78.10620.21L       C805H58                      C655
79.10710.2AL       CT7343H83                    C657
79.10710.2AL       CT7343H83                    C658
78.10421.2FL       C402H22                      C659
78.10620.21L       C805H58                      C660
78.10521.2BL       C603H36                      C670
078.10621.0211     C805H58                      C671
078.10621.0211     C805H58                      C672
78.10521.2BL       C603H36                      C998
78.10421.2FL       C402H22                      C999
78.22522.21L       C805H54                      CA1
020.80818.0001     PREFIT-200P-360520-1H542     CN1
83.SMF15.0AH       SOD123AK-2H43                D1
083.5V0X1.00AF     SOD523AKH26                  D2
083.5V0X1.00AF     SOD523AKH26                  D3
83.SMF15.0AH       SOD123AK-2H43                D4
83.R2003.K8F       SOD323AKH42                  D11
75.005V0.A77       SOD882-10D6-1H20             D13
75.005V0.A77       SOD882-10D6-1H20             D14
75.005V0.A77       SOD882-10D6-1H20             D15
75.005V0.A77       SOD882-10D6-1H20             D16
75.005V0.A77       SOD882-10D6-1H20             D17
83.0005V.MAF       SOD882-10D6-1H20             D18
83.0005V.MAF       SOD882-10D6-1H20             D19
ZZ.C0N2C.011       GAP-CLOSE-PWR-4              G1
ZZ.CON2C.XXX       CON2C-U                      G2
ZZ.CON2C.XXX       CON2C-U                      G3
ZZ.C0N2C.011       GAP-CLOSE-PWR-4              G4
ZZ.CON2C.XXX       CON2C-U                      G5
ZZ.CON2C.XXX       CON2C-U                      G10
68.00201.141       L2012-4P-1MH40               L1
68.00109.171       L805H42                      L2
68.00109.171       L805H42                      L3
68.00109.171       L805H42                      L4
68.00109.171       L805H42                      L5
68.00084.831       L20125H42                    L6
68.4R71A.20Q       L11102530H158                L7
68.00084.831       L20125H42                    L8
68.3R310.20V       L7066-1830-UH119             L9
068.3R310.2091     L4947-1215H119               L10
68.00084.A61       L20125H42                    L23
68.00084.831       L20125H42                    L30
68.1R010.20K       L109100-2430-UH119           L31
06.WP130.14A       LED-100-3PH206               LED3
83.01921.S70       LED1608AKH40                 LED6
020.C0085.0075     MDT580M01001                 M1
020.C0085.0075     MDT580M01001                 M2
20.F1354.120       61082-121402LF-U1            MEZZ1
087.71242.0465     STF256R168H278               NUT1
082.20005.0001     OSC-3225-4P-3H48             OSC1
ZZ.00PAD.M21       0R0603-PAD-1-U               P1
84.03904.T11       SOT23CBE2D4H44               PQ1
84.2N702.031       SOT23DGS2D4H44               PQ2
84.08878.A37       SOIC8H69                     PQ3
74.53318.073       DFN22G6050-G6133H60          PU1
74.53318.073       DFN22G6050-G6133H60          PU2
74.53312.073       QFN16G3-G1D7H40              PU4
74.74801.A33       QFN20-1G3D15H40              PU9
74.74801.A33       QFN20-1G3D15H40              PU10
74.74801.A33       QFN20-1G3D15H40              PU11
022.40001.0221     DTSA-65N-K-S-V-676-K         PWR1
84.03904.T11       SOT23CBE2D4H44               Q2
84.03904.T11       SOT23CBE2D4H44               Q3
84.2N702.031       SOT23DGS2D4H44               Q4
084.00925.003N     LFPAK-5PH48-U                Q5
84.2N702.031       SOT23DGS2D4H44               Q11
84.2N702.031       SOT23DGS2D4H44               Q12
84.2N702.031       SOT23DGS2D4H44               Q20
84.2N702.031       SOT23DGS2D4H44               Q21
84.2N702.031       SOT23DGS2D4H44               Q24
84.2N702.031       SOT23DGS2D4H44               Q25
84.2N702.031       SOT23DGS2D4H44               Q26
84.06P39.03F       UMT6H30                      Q27
84.2N702.031       SOT23DGS2D4H44               Q28
64.47015.6DL       R402H16                      R3
63.R0034.1DL       R402H16                      R4
63.R0034.1DL       R402H16                      R5
63.R0034.1DL       R402H16                      R7
63.R0034.1DL       R402H16                      R8
63.R0034.1DL       R402H16                      R9
63.R0034.1DL       R402H16                      R10
63.R0034.1DL       R402H16                      R14
63.R0034.1DL       R402H16                      R15
64.10025.6DL       R402H16                      R16
64.47015.6DL       R402H16                      R18
64.47015.6DL       R402H16                      R19
64.47015.6DL       R402H16                      R20
64.47015.6DL       R402H16                      R21
64.47015.6DL       R402H16                      R22
64.47015.6DL       R402H16                      R23
64.10025.6DL       R402H16                      R24
64.15025.6DL       R402H16                      R25
63.R0034.1DL       R402H16                      R26
64.10045.6DL       R402H16                      R27
63.12334.1DL       R402H16                      R28
64.47015.6DL       R402H16                      R29
64.47015.6DL       R402H16                      R30
64.47015.6DL       R402H16                      R31
64.47015.6DL       R402H16                      R32
64.47015.6DL       R402H16                      R33
64.47015.6DL       R402H16                      R34
64.47015.6DL       R402H16                      R35
64.47015.6DL       R402H16                      R36
64.10045.6DL       R402H16                      R37
63.R0034.1DL       R402H16                      R38
63.R0034.1DL       R402H16                      R39
64.47015.6DL       R402H16                      R40
64.47015.6DL       R402H16                      R41
64.47015.6DL       R402H16                      R42
64.47015.6DL       R402H16                      R43
64.10045.6DL       R402H16                      R45
63.R0034.1DL       R402H16                      R46
64.10045.6DL       R402H16                      R47
64.47015.6DL       R402H16                      R48
64.10025.6DL       R402H16                      R49
64.47015.6DL       R402H16                      R50
64.33R05.6DL       R402H16                      R51
64.33R05.6DL       R402H16                      R52
64.47015.6DL       R402H16                      R53
64.10025.6DL       R402H16                      R56
64.33R05.6DL       R402H16                      R58
64.33R05.6DL       R402H16                      R59
64.10025.6DL       R402H16                      R64
63.82234.1DL       R402H16                      R65
64.47515.6DL       R402H16                      R71
64.10025.6DL       R402H16                      R72
64.47515.6DL       R402H16                      R73
63.R0034.1DL       R402H16                      R74
63.R0034.1DL       R402H16                      R75
64.47025.6DL       R402H16                      R76
64.10025.6DL       R402H16                      R77
64.10025.6DL       R402H16                      R78
64.47035.6DL       R402H16                      R79
64.10035.6DL       R402H16                      R80
64.47515.6DL       R402H16                      R81
64.10025.6DL       R402H16                      R82
63.22234.1DL       R402H16                      R83
64.47015.6DL       R402H16                      R84
64.10035.6DL       R402H16                      R85
63.22234.1DL       R402H16                      R86
64.10035.6DL       R402H16                      R87
64.10035.6DL       R402H16                      R88
64.33R25.6DL       R402H16                      R89
63.22234.1DL       R402H16                      R90
64.30005.6DL       R402H16                      R91
63.R0034.1DL       R402H16                      R92
63.R0034.1DL       R402H16                      R93
63.R0034.1DL       R402H16                      R95
63.R0034.1DL       R402H16                      R96
63.R0034.1DL       R402H16                      R97
63.R0034.1DL       R402H16                      R98
63.R0034.1DL       R402H16                      R99
63.R0034.1DL       R402H16                      R100
63.R0034.1DL       R402H16                      R101
63.R0034.1DL       R402H16                      R102
64.47015.6DL       R402H16                      R105
63.R0034.1DL       R402H16                      R123
63.R0034.1DL       R402H16                      R124
63.R0034.1DL       R402H16                      R127
63.R0034.1DL       R402H16                      R128
63.R0034.1DL       R402H16                      R129
63.R0034.1DL       R402H16                      R130
63.R0034.1DL       R402H16                      R131
63.R0034.1DL       R402H16                      R132
63.82234.1DL       R402H16                      R133
63.82234.1DL       R402H16                      R134
63.82234.1DL       R402H16                      R135
63.82234.1DL       R402H16                      R136
63.82234.1DL       R402H16                      R137
63.82234.1DL       R402H16                      R138
63.82234.1DL       R402H16                      R139
64.10035.6DL       R402H16                      R140
64.10016.6DL       R402H16                      R141
64.20005.6DL       R402H16                      R142
64.10016.6DL       R402H16                      R143
64.47015.6DL       R402H16                      R144
64.24005.6DL       R402H16                      R145
64.10035.6DL       R402H16                      R146
64.10035.6DL       R402H16                      R147
64.10035.6DL       R402H16                      R148
64.10035.6DL       R402H16                      R149
63.R0034.1DL       R402H16                      R151
63.R0034.1DL       R402H16                      R152
63.R0034.1DL       R402H16                      R153
63.R0034.1DL       R402H16                      R154
63.R0034.1DL       R402H16                      R155
63.R0034.1DL       R402H16                      R156
63.R0034.1DL       R402H16                      R157
63.R0034.1DL       R402H16                      R158
63.R0034.1DL       R402H16                      R159
63.R0034.1DL       R402H16                      R160
63.R0034.1DL       R402H16                      R161
63.R0034.1DL       R402H16                      R162
63.R0034.1DL       R402H16                      R163
63.R0034.1DL       R402H16                      R164
63.R0034.1DL       R402H16                      R165
63.R0034.1DL       R402H16                      R166
63.R0034.1DL       R402H16                      R167
63.R0034.1DL       R402H16                      R168
63.R0034.1DL       R402H16                      R169
63.R0034.1DL       R402H16                      R170
63.R0034.1DL       R402H16                      R171
63.R0034.1DL       R402H16                      R172
63.R0034.1DL       R402H16                      R173
63.R0034.1DL       R402H16                      R174
63.R0034.1DL       R402H16                      R175
63.R0034.1DL       R402H16                      R176
63.R0034.1DL       R402H16                      R177
63.R0034.1DL       R402H16                      R178
64.22015.6DL       R402H16                      R179
64.22015.6DL       R402H16                      R180
64.22015.6DL       R402H16                      R181
64.22015.6DL       R402H16                      R182
64.22015.6DL       R402H16                      R183
64.22015.6DL       R402H16                      R184
64.22015.6DL       R402H16                      R185
64.22015.6DL       R402H16                      R186
64.22015.6DL       R402H16                      R187
64.22015.6DL       R402H16                      R188
64.49905.6DL       R402H16                      R189
64.49905.6DL       R402H16                      R190
64.22015.6DL       R402H16                      R191
64.22015.6DL       R402H16                      R192
64.20025.6DL       R402H16                      R193
64.20025.6DL       R402H16                      R194
64.22015.6DL       R402H16                      R195
64.22015.6DL       R402H16                      R196
64.22015.6DL       R402H16                      R197
64.10015.6DL       R402H16                      R198
64.10015.6DL       R402H16                      R199
64.22015.6DL       R402H16                      R200
64.22015.6DL       R402H16                      R201
64.22015.6DL       R402H16                      R202
64.22015.6DL       R402H16                      R203
64.22015.6DL       R402H16                      R204
64.60R45.6DL       R402H16                      R205
64.60R45.6DL       R402H16                      R206
64.12005.6DL       R402H16                      R207
64.12005.6DL       R402H16                      R208
64.12005.6DL       R402H16                      R209
64.12005.6DL       R402H16                      R210
64.12005.6DL       R402H16                      R211
64.12005.6DL       R402H16                      R212
64.12005.6DL       R402H16                      R213
64.27015.6DL       R402H16                      R214
64.12005.6DL       R402H16                      R215
64.12005.6DL       R402H16                      R216
64.12005.6DL       R402H16                      R217
64.12005.6DL       R402H16                      R218
64.24005.6DL       R402H16                      R219
64.12005.6DL       R402H16                      R220
64.12005.6DL       R402H16                      R221
64.12005.6DL       R402H16                      R222
64.12005.6DL       R402H16                      R223
64.47015.6DL       R402H16                      R224
64.12005.6DL       R402H16                      R225
64.12005.6DL       R402H16                      R226
64.12005.6DL       R402H16                      R227
64.12005.6DL       R402H16                      R228
64.12005.6DL       R402H16                      R229
64.12005.6DL       R402H16                      R230
64.12005.6DL       R402H16                      R231
64.12005.6DL       R402H16                      R232
64.12005.6DL       R402H16                      R233
64.12005.6DL       R402H16                      R234
64.12005.6DL       R402H16                      R235
64.12005.6DL       R402H16                      R236
64.12005.6DL       R402H16                      R237
64.12005.6DL       R402H16                      R238
63.R0034.1DL       R402H16                      R239
64.12005.6DL       R402H16                      R240
64.12005.6DL       R402H16                      R241
64.12005.6DL       R402H16                      R242
64.12005.6DL       R402H16                      R243
64.12005.6DL       R402H16                      R244
64.12005.6DL       R402H16                      R245
64.12005.6DL       R402H16                      R246
64.12005.6DL       R402H16                      R247
64.12005.6DL       R402H16                      R248
64.12005.6DL       R402H16                      R249
64.12005.6DL       R402H16                      R250
64.12005.6DL       R402H16                      R251
64.12005.6DL       R402H16                      R252
64.12005.6DL       R402H16                      R253
64.12005.6DL       R402H16                      R254
64.12005.6DL       R402H16                      R255
64.12005.6DL       R402H16                      R256
64.12005.6DL       R402H16                      R257
64.12005.6DL       R402H16                      R258
64.12005.6DL       R402H16                      R259
64.12005.6DL       R402H16                      R260
64.12005.6DL       R402H16                      R261
64.47015.6DL       R402H16                      R262
64.47015.6DL       R402H16                      R263
64.47015.6DL       R402H16                      R264
64.47015.6DL       R402H16                      R265
63.22234.1DL       R402H16                      R266
63.22234.1DL       R402H16                      R267
63.22234.1DL       R402H16                      R268
63.22234.1DL       R402H16                      R269
64.33R05.6DL       R402H16                      R270
64.47015.6DL       R402H16                      R271
64.47015.6DL       R402H16                      R272
64.47015.6DL       R402H16                      R273
64.22015.6DL       R402H16                      R274
64.10035.6DL       R402H16                      R275
64.47015.6DL       R402H16                      R276
64.33R05.6DL       R402H16                      R277
63.R0034.1DL       R402H16                      R278
63.R0034.1DL       R402H16                      R279
64.33R05.6DL       R402H16                      R280
63.R0034.1DL       R402H16                      R281
64.47015.6DL       R402H16                      R282
64.33R05.6DL       R402H16                      R283
64.33R05.6DL       R402H16                      R284
64.47015.6DL       R402H16                      R285
63.R0034.1DL       R402H16                      R286
63.R0034.1DL       R402H16                      R287
63.R0034.1DL       R402H16                      R288
63.R0034.1DL       R402H16                      R289
63.R0034.1DL       R402H16                      R290
63.R0034.1DL       R402H16                      R291
63.R0034.1DL       R402H16                      R292
63.R0034.1DL       R402H16                      R293
63.R0034.1DL       R402H16                      R294
63.R0034.1DL       R402H16                      R295
64.22015.6DL       R402H16                      R296
63.R0034.1DL       R402H16                      R297
63.R0034.1DL       R402H16                      R298
64.47015.6DL       R402H16                      R299
64.47015.6DL       R402H16                      R300
63.R0034.1DL       R402H16                      R301
63.R0034.1DL       R402H16                      R302
64.47025.6DL       R402H16                      R303
64.47025.6DL       R402H16                      R304
64.10025.6DL       R402H16                      R305
63.33034.1DL       R402H16                      R306
64.10025.6DL       R402H16                      R307
64.47015.6DL       R402H16                      R308
64.47015.6DL       R402H16                      R309
64.47015.6DL       R402H16                      R310
64.47015.6DL       R402H16                      R311
63.R0034.1DL       R402H16                      R312
64.47015.6DL       R402H16                      R313
63.R0034.1DL       R402H16                      R314
64.10025.6DL       R402H16                      R315
63.R0034.1DL       R402H16                      R316
63.R0034.1DL       R402H16                      R317
63.R0034.1DL       R402H16                      R318
63.R0034.1DL       R402H16                      R319
63.R0034.1DL       R402H16                      R320
63.R0034.1DL       R402H16                      R321
63.R0034.1DL       R402H16                      R322
64.47015.6DL       R402H16                      R323
64.47015.6DL       R402H16                      R324
63.R0034.1DL       R402H16                      R325
63.R0034.1DL       R402H16                      R326
64.47015.6DL       R402H16                      R327
63.R0034.1DL       R402H16                      R328
63.R0034.1DL       R402H16                      R329
64.47015.6DL       R402H16                      R330
64.47015.6DL       R402H16                      R331
64.47015.6DL       R402H16                      R332
63.R0034.1DL       R402H16                      R333
63.R0034.1DL       R402H16                      R334
63.R0034.1DL       R402H16                      R335
64.47015.6DL       R402H16                      R336
64.47015.6DL       R402H16                      R337
63.82234.1DL       R402H16                      R338
64.47015.6DL       R402H16                      R339
63.82234.1DL       R402H16                      R340
64.47015.6DL       R402H16                      R341
63.R0034.1DL       R402H16                      R342
63.R0034.1DL       R402H16                      R343
63.R0034.1DL       R402H16                      R344
63.R0034.1DL       R402H16                      R345
64.15005.6DL       R402H16                      R346
64.47015.6DL       R402H16                      R347
63.R0034.1DL       R402H16                      R348
64.10035.6DL       R402H16                      R349
63.R0034.1DL       R402H16                      R350
64.10025.6DL       R402H16                      R351
64.47015.6DL       R402H16                      R352
64.47015.6DL       R402H16                      R353
64.47015.6DL       R402H16                      R354
64.47015.6DL       R402H16                      R355
63.R0034.1DL       R402H16                      R356
64.47015.6DL       R402H16                      R357
64.10025.6DL       R402H16                      R358
64.10025.6DL       R402H16                      R359
64.10025.6DL       R402H16                      R360
64.10025.6DL       R402H16                      R361
64.47015.6DL       R402H16                      R362
64.47015.6DL       R402H16                      R363
64.47015.6DL       R402H16                      R364
64.47015.6DL       R402H16                      R365
64.49925.6DL       R402H16                      R366
064.18025.06DL     R402H16                      R367
63.R0034.1DL       R402H16                      R368
64.47015.6DL       R402H16                      R369
64.47015.6DL       R402H16                      R370
64.47015.6DL       R402H16                      R371
64.47015.6DL       R402H16                      R372
64.47015.6DL       R402H16                      R373
64.47015.6DL       R402H16                      R374
64.47015.6DL       R402H16                      R375
64.47015.6DL       R402H16                      R376
64.47015.6DL       R402H16                      R377
64.47015.6DL       R402H16                      R378
64.47015.6DL       R402H16                      R379
64.47015.6DL       R402H16                      R380
64.47015.6DL       R402H16                      R381
64.47015.6DL       R402H16                      R382
64.47015.6DL       R402H16                      R383
64.47015.6DL       R402H16                      R384
64.47015.6DL       R402H16                      R385
64.47015.6DL       R402H16                      R386
64.47015.6DL       R402H16                      R387
64.47015.6DL       R402H16                      R388
64.47015.6DL       R402H16                      R389
64.47015.6DL       R402H16                      R390
64.47015.6DL       R402H16                      R391
64.47015.6DL       R402H16                      R392
64.47015.6DL       R402H16                      R393
64.47015.6DL       R402H16                      R394
64.47015.6DL       R402H16                      R395
64.47015.6DL       R402H16                      R396
64.47015.6DL       R402H16                      R397
64.47015.6DL       R402H16                      R398
64.47015.6DL       R402H16                      R399
64.47015.6DL       R402H16                      R400
64.78715.6DL       R402H16                      R401
64.33005.6DL       R402H16                      R402
63.R0034.1DL       R402H16                      R403
64.10015.6DL       R402H16                      R404
64.10015.6DL       R402H16                      R405
63.R0034.1DL       R402H16                      R406
64.14015.6DL       R402H16                      R407
64.47015.6DL       R402H16                      R408
64.14015.6DL       R402H16                      R409
64.10015.6DL       R402H16                      R410
63.R0034.1DL       R402H16                      R411
64.10015.6DL       R402H16                      R412
64.27015.6DL       R402H16                      R413
64.10015.6DL       R402H16                      R415
64.47015.6DL       R402H16                      R416
63.R0034.1DL       R402H16                      R417
63.R0034.1DL       R402H16                      R418
63.R0034.1DL       R402H16                      R419
64.47015.6DL       R402H16                      R420
64.10025.6DL       R402H16                      R421
64.47015.6DL       R402H16                      R422
64.47015.6DL       R402H16                      R423
64.47015.6DL       R402H16                      R424
64.47015.6DL       R402H16                      R425
63.R0034.1DL       R402H16                      R426
63.R0034.1DL       R402H16                      R427
64.47015.6DL       R402H16                      R428
64.47015.6DL       R402H16                      R429
64.47015.6DL       R402H16                      R430
64.10R05.6DL       R402H14                      R431
64.10006.6DL       R402H14                      R432
64.39225.6DL       R402H16                      R433
64.10006.6DL       R402H14                      R434
64.26125.6DL       R402H16                      R435
63.R0034.1DL       R402H16                      R436
64.10035.6DL       R402H16                      R437
63.10334.1DL       R402H16                      R438
64.11025.6DL       R402H16                      R439
64.10R05.6DL       R402H14                      R440
64.10R05.6DL       R402H14                      R441
64.10R05.6DL       R402H14                      R442
64.10R05.6DL       R402H14                      R443
64.R0025.L1L       RL3115-4PH45                 R444
64.49925.6DL       R402H16                      R445
64.49925.6DL       R402H16                      R446
064.41215.06DS     R402H16                      R447
064.51015.06DS     R402H16                      R448
63.10234.1DL       R402H16                      R449
64.10R05.16L       R805H24                      R450
64.10025.6DL       R402H16                      R451
63.R0034.1DL       R402H16                      R452
63.10434.L1L       R402H15                      R453
64.66525.6DL       R402H16                      R454
63.10533.15L       R603H22                      R455
63.R0034.1DL       R402H16                      R456
63.10434.L1L       R402H15                      R457
64.86625.6DL       R402H16                      R458
63.R0034.1DL       R402H16                      R459
63.R0034.1DL       R402H16                      R460
63.10434.L1L       R402H15                      R461
64.22625.6DL       R402H16                      R462
64.10025.6DL       R402H16                      R463
64.2R205.55L       R603H22                      R464
64.22015.6DL       R402H16                      R465
63.2R734.15L       R603H22                      R466
64.10025.6DL       R402H16                      R467
63.33234.1DL       R402H16                      R468
64.3R015.16L       R805H24                      R469
64.20035.6DL       R402H16                      R470
64.15025.6DL       R402H16                      R471
64.10035.6DL       R402H16                      R472
64.10R05.55L       R603H22                      R473
64.73225.6DL       R402H16                      R474
64.57626.6DL       R402H16                      R475
64.86635.6DL       R402H16                      R476
64.61935.6DL       R402H16                      R477
64.10025.6DL       R402H16                      R478
63.R0032.11L       R1206H28                     R479
63.R0032.11L       R1206H28                     R480
63.R0032.11L       R1206H28                     R481
63.10334.1DL       R402H16                      R482
63.2R233.15L       R603H22                      R483
64.3R015.16L       R805H24                      R484
63.R0034.1DL       R402H16                      R485
64.38315.6DL       R402H16                      R486
64.10025.6DL       R402H16                      R487
64.27015.6DL       R402H16                      R488
64.10R05.55L       R603H22                      R489
64.3R015.16L       R805H24                      R490
64.15025.6DL       R402H16                      R491
64.47535.6DL       R402H16                      R492
64.10035.6DL       R402H16                      R493
64.57626.6DL       R402H16                      R494
64.86635.6DL       R402H16                      R495
64.44225.6DL       R402H16                      R496
64.61935.6DL       R402H16                      R497
63.R0034.1DL       R402H16                      R498
64.10025.6DL       R402H16                      R499
63.22234.1DL       R402H16                      R500
64.47015.6DL       R402H16                      R501
63.22234.1DL       R402H16                      R502
64.10045.6DL       R402H16                      R503
63.R0031.16L       R805H24                      R504
64.35715.6DL       R402H16                      R505
64.16915.6DL       R402H16                      R506
64.10025.6DL       R402H16                      R507
63.R0034.1DL       R402H16                      R508
64.47515.6DL       R402H16                      R509
63.R0034.1DL       R402H16                      R510
64.2R205.55L       R603H22                      R511
63.R0032.11L       R1206H28                     R512
64.10025.6DL       R402H16                      R513
64.10R05.55L       R603H22                      R514
64.13725.6DL       R402H16                      R515
63.R0034.1DL       R402H16                      R516
63.R0034.1DL       R402H16                      R517
64.10025.6DL       R402H16                      R518
64.10015.6DL       R402H16                      R519
64.3R015.16L       R805H24                      R520
64.15025.6DL       R402H16                      R521
63.R0034.1DL       R402H16                      R522
64.10015.6DL       R402H16                      R523
63.R0034.1DL       R402H16                      R524
63.R0034.1DL       R402H16                      R525
63.R0034.1DL       R402H16                      R526
63.R0034.1DL       R402H16                      R527
63.R0034.1DL       R402H16                      R528
63.R0031.16L       R805H24                      R529
64.24915.6DL       R402H16                      R530
64.49915.6DL       R402H16                      R531
64.10025.6DL       R402H16                      R532
63.R0034.1DL       R402H16                      R533
64.47515.6DL       R402H16                      R534
63.R0034.1DL       R402H16                      R535
63.R0031.16L       R805H24                      R536
29L2161AA          R402H16                      R537
64.46415.6DL       R402H16                      R538
64.10025.6DL       R402H16                      R539
63.R0034.1DL       R402H16                      R540
64.47515.6DL       R402H16                      R541
63.R0034.1DL       R402H16                      R542
64.47015.6DL       R402H16                      R544
64.47015.6DL       R402H16                      R545
64.47015.6DL       R402H16                      R546
64.47015.6DL       R402H16                      R547
64.47015.6DL       R402H16                      R548
64.47015.6DL       R402H16                      R549
64.47015.6DL       R402H16                      R550
64.47015.6DL       R402H16                      R551
64.47015.6DL       R402H16                      R552
64.47015.6DL       R402H16                      R553
64.47015.6DL       R402H16                      R554
64.47015.6DL       R402H16                      R555
63.R0034.1DL       R402H16                      R556
63.R0034.1DL       R402H16                      R557
63.R0034.1DL       R402H16                      R558
63.R0034.1DL       R402H16                      R559
64.47015.6DL       R402H16                      R599
64.47015.6DL       R402H16                      R601
63.R0034.1DL       R402H16                      R607
64.10035.6DL       R402H16                      R610
63.R0034.1DL       R402H16                      R617
63.R0034.1DL       R402H16                      R651
64.10015.6DL       R402H16                      R695
64.47015.6DL       R402H16                      R697
64.47015.6DL       R402H16                      R698
64.47015.6DL       R402H16                      R699
64.47015.6DL       R402H16                      R700
64.47015.6DL       R402H16                      R701
64.47015.6DL       R402H16                      R702
64.47015.6DL       R402H16                      R703
64.47015.6DL       R402H16                      R705
64.47015.6DL       R402H16                      R706
64.47015.6DL       R402H16                      R707
64.10025.6DL       R402H16                      R708
63.R0031.16L       R805H24                      R709
63.R0031.16L       R805H24                      R710
63.R0034.1DL       R402H16                      R711
63.R0034.1DL       R402H16                      R712
63.R0034.1DL       R402H16                      R713
63.R0034.1DL       R402H16                      R714
63.R0034.1DL       R402H16                      R715
64.10025.6DL       R402H16                      R716
63.R0034.1DL       R402H16                      R717
63.R0034.1DL       R402H16                      R718
63.10434.L1L       R402H15                      R719
63.R0034.1DL       R402H16                      R720
64.47015.6DL       R402H16                      R721
63.10334.1DL       R402H16                      R722
64.47015.6DL       R402H16                      R723
63.R0034.1DL       R402H16                      R724
64.47015.6DL       R402H16                      R725
64.47015.6DL       R402H16                      R726
63.R0034.1DL       R402H16                      R727
64.47015.6DL       R402H16                      R728
64.10025.6DL       R402H16                      R729
63.R0034.1DL       R402H16                      R731
63.R0034.1DL       R402H16                      R732
63.R0034.1DL       R402H16                      R734
63.R0034.1DL       R402H16                      R736
64.12005.55L       R603H22                      R737
64.47015.6DL       R402H16                      R740
64.10025.6DL       R402H16                      R742
64.10035.6DL       R402H16                      R743
64.11025.6DL       R402H16                      R744
63.33034.1DL       R402H16                      R763
63.R0034.1DL       R402H16                      R764
63.R0034.1DL       R402H16                      R765
63.33034.1DL       R402H16                      R766
63.R0034.1DL       R402H16                      R767
63.R0034.1DL       R402H16                      R768
63.R0034.1DL       R402H16                      R769
63.R0034.1DL       R402H16                      R770
63.R0034.1DL       R402H16                      R771
63.R0034.1DL       R402H16                      R772
63.R0034.1DL       R402H16                      R773
64.10015.6DL       R402H16                      R774
64.10015.6DL       R402H16                      R775
64.10015.6DL       R402H16                      R776
64.10015.6DL       R402H16                      R777
64.86605.6DL       R402H16                      R778
64.10015.6DL       R402H16                      R779
63.R0034.1DL       R402H16                      R780
63.R0034.1DL       R402H16                      R781
64.47015.6DL       R402H16                      R782
64.10025.6DL       R402H16                      R783
64.10025.6DL       R402H16                      R784
64.10025.6DL       R402H16                      R785
63.R0034.1DL       R402H16                      R786
63.R0034.1DL       R402H16                      R787
63.R0034.1DL       R402H16                      R795
63.R0034.1DL       R402H16                      R796
63.R0034.1DL       R402H16                      R797
64.47015.6DL       R402H16                      R801
64.47015.6DL       R402H16                      R802
64.47015.6DL       R402H16                      R803
64.47015.6DL       R402H16                      R804
64.47015.6DL       R402H16                      R805
64.47015.6DL       R402H16                      R806
64.47015.6DL       R402H16                      R807
63.R0034.1DL       R402H16                      R808
63.R0034.1DL       R402H16                      R809
63.R0034.1DL       R402H16                      R810
64.47015.6DL       R402H16                      R811
64.47015.6DL       R402H16                      R812
64.10015.6DL       R402H16                      R813
64.10015.6DL       R402H16                      R814
64.10015.6DL       R402H16                      R815
64.10015.6DL       R402H16                      R816
64.13005.55L       R603H22                      R817
64.14015.6DL       R402H16                      R819
63.R0034.1DL       R402H16                      R820
64.10015.6DL       R402H16                      R821
63.R0034.1DL       R402H16                      R822
64.39225.6DL       R402H16                      R824
64.10025.6DL       R402H16                      R825
64.10025.6DL       R402H16                      R826
64.10025.6DL       R402H16                      R828
64.10R05.55L       R603H22                      R829
64.20025.6DL       R402H16                      R831
64.2R205.55L       R603H22                      R832
64.20035.6DL       R402H16                      R833
64.20035.6DL       R402H16                      R834
64.20015.6DL       R402H16                      R836
63.2R734.15L       R603H22                      R837
64.3R015.16L       R805H24                      R838
64.10025.6DL       R402H16                      R839
64.44225.6DL       R402H16                      R840
64.39225.6DL       R402H16                      R841
64.30935.6DL       R402H16                      R842
64.14735.L1L       R402H16                      R843
64.30935.6DL       R402H16                      R844
64.47015.6DL       R402H16                      R845
64.47015.6DL       R402H16                      R846
022.40001.0681     DIPTRONICS                   RST1
62.10089.021       SKT-SOIC16-153139H258        SKT1
62.10089.021       SKT-SOIC16-153139H258        SKT2
ZZ.PAD28.XXX       TPAD28                       TP4
ZZ.PAD28.XXX       TPAD28                       TP5
ZZ.PAD28.XXX       TPAD28                       TP6
ZZ.PAD28.XXX       TPAD28                       TP9
ZZ.PAD28.XXX       TPAD28                       TP10
ZZ.PAD28.XXX       TPAD28                       TP11
ZZ.PAD28.XXX       TPAD28                       TP12
ZZ.PAD28.XXX       TPAD28                       TP13
ZZ.PAD28.XXX       TPAD28                       TP17
ZZ.PAD28.XXX       TPAD28                       TP18
ZZ.0TPAD.191       TPAD32                       TP19
ZZ.PAD28.XXX       TPAD28                       TP27
ZZ.PAD28.XXX       TPAD28                       TP28
ZZ.PAD28.XXX       TPAD28                       TP29
ZZ.PAD28.XXX       TPAD28                       TP50
ZZ.PAD28.XXX       TPAD28                       TP51
ZZ.PAD28.XXX       TPAD28                       TP52
ZZ.PAD28.XXX       TPAD28                       TP53
ZZ.PAD28.XXX       TPAD28                       TP54
ZZ.PAD28.XXX       TPAD28                       TP55
ZZ.PAD28.XXX       TPAD28                       TP57
ZZ.PAD28.XXX       TPAD28                       TP62
ZZ.PAD28.XXX       TPAD28                       TP63
ZZ.PAD28.XXX       TPAD28                       TP64
ZZ.PAD28.XXX       TPAD28                       TP65
ZZ.PAD28.XXX       TPAD28                       TP66
ZZ.PAD28.XXX       TPAD28                       TP70
ZZ.PAD28.XXX       TPAD28                       TP71
ZZ.PAD28.XXX       TPAD28                       TP72
ZZ.PAD28.XXX       TPAD28                       TP73
ZZ.PAD28.XXX       TPAD28                       TP74
ZZ.PAD28.XXX       TPAD28                       TP75
ZZ.PAD28.XXX       TPAD28                       TP76
ZZ.PAD28.XXX       TPAD28                       TP77
ZZ.PAD28.XXX       TPAD28                       TP78
ZZ.PAD28.XXX       TPAD28                       TP79
ZZ.PAD28.XXX       TPAD28                       TP80
ZZ.PAD28.XXX       TPAD28                       TP81
ZZ.PAD28.XXX       TPAD28                       TP82
ZZ.PAD28.XXX       TPAD28                       TP83
ZZ.PAD28.XXX       TPAD28                       TP84
ZZ.PAD28.XXX       TPAD28                       TP186
ZZ.PAD28.XXX       TPAD28                       TP187
ZZ.PAD28.XXX       TPAD28                       TP188
ZZ.PAD28.XXX       TPAD28                       TP189
ZZ.PAD28.XXX       TPAD28                       TP190
ZZ.PAD28.XXX       TPAD28                       TP191
ZZ.PAD28.XXX       TPAD28                       TP203
ZZ.PAD28.XXX       TPAD28                       TP204
ZZ.PAD28.XXX       TPAD28                       TP205
ZZ.PAD28.XXX       TPAD28                       TP206
ZZ.PAD28.XXX       TPAD28                       TP207
ZZ.PAD28.XXX       TPAD28                       TP208
ZZ.PAD28.XXX       TPAD28                       TP209
ZZ.PAD28.XXX       TPAD28                       TP210
ZZ.PAD28.XXX       TPAD28                       TP211
ZZ.PAD28.XXX       TPAD28                       TP212
ZZ.PAD28.XXX       TPAD28                       TP213
ZZ.PAD28.XXX       TPAD28                       TP214
ZZ.0TPAD.191       TPAD32                       TP215
ZZ.0TPAD.191       TPAD32                       TP216
ZZ.PAD28.XXX       TPAD28                       TP218
020.F0528.0011     91932-31111LF                TPM1
071.02500.0B0U     BGA456D19H58                 U2
73.02G07.A2J       SOT-363H44                   U5
73.01G07.01H       SC70-5H44                    U9
74.00331.A2F       SC70-5H44                    U10
072.25256.0B01     SOIC16-6H104                 U11
073.03166.000B     SC70-5H44                    U12
073.03166.000B     SC70-5H44                    U15
073.03166.000B     SC70-5H44                    U16
073.01G74.0001     SSOIC8-4H36                  U19
72.02464.A01       SOIC8H69                     U26
74.00075.B79       MSOP8-1H44                   U27
072.00546.0A0U     BGA96D075130H48              U28
72.25635.A01       SOIC16-6H105                 U29
71.00551.00A       SOIC8H69                     U30
73.01G08.L03       SC70-5H44                    U31
73.74126.BHB       SSOIC14-1H48                 U32
74.23157.A99       MSOP10H44                    U33
071.09555.000W     TSOIC24H48                   U34
074.01278.0A7Z     QFN32-G3D45-UH32             U35
73.01G08.L03       SC70-5H44                    U37
73.01G08.L03       SC70-5H44                    U38
71.09306.00I       SSOIC8H52                    U45
73.01G08.L03       SC70-5H44                    U46
74.53319.073       QFN22G6050-G6133H60          U81
71.09306.00I       SSOIC8H52                    U82
71.09306.00I       SSOIC8H52                    U83
74.00075.B79       MSOP8-1H44                   U84
74.00075.B79       MSOP8-1H44                   U85
74.02065.07F       SOT-23-5H58                  U98
71.02514.F03       QFN36-G3D85H40               U99
73.1G126.DHG       SC70-5H44                    U100
73.1G126.DHG       SC70-5H44                    U101
73.01G14.L05       SC70-5H44                    U102
73.1G126.DHG       SC70-5H44                    U103
73.1G126.DHG       SC70-5H44                    U104
73.03245.F0B       TSOIC20H48                   U105
73.01G14.AHG       SOT-23-5H58                  U106
73.03245.F0B       TSOIC20H48                   U107
022.10005.0I61     SKT-USB13-064258             USB1
ZZ.00PAD.MP1       VIA-PCIE-4P-368076           VIA1
ZZ.00PAD.MP1       VIA-PCIE-4P-368076           VIA2
ZZ.00PAD.MP1       VIA-PCIE-4P-368076           VIA3
ZZ.00PAD.MP1       VIA-PCIE-4P-368076           VIA4
ZZ.00PAD.MP1       VIA-PCIE-4P-368076           VIA5
ZZ.00PAD.MP1       VIA-PCIE-4P-368076           VIA6
ZZ.00PAD.MP1       VIA-PCIE-4P-368076           VIA7
ZZ.00PAD.MP1       VIA-PCIE-4P-368076           VIA8
ZZ.00PAD.MP1       VIA-PCIE-4P-368076           VIA9
ZZ.00PAD.MP1       VIA-PCIE-4P-368076           VIA10
ZZ.00PAD.MP1       VIA-PCIE-4P-368076           VIA11
ZZ.00PAD.MP1       VIA-PCIE-4P-368076           VIA12
ZZ.00PAD.MP1       VIA-PCIE-4P-368076           VIA13
ZZ.00PAD.MP1       VIA-PCIE-4P-368076           VIA14
ZZ.00PAD.MP1       VIA-PCIE-4P-368076           VIA15
ZZ.00PAD.MP1       VIA-PCIE-4P-368076           VIA16
ZZ.00PAD.MP1       VIA-PCIE-4P-368076           VIA25
ZZ.00PAD.MP1       VIA-PCIE-4P-368076           VIA50
ZZ.00PAD.MP1       VIA-PCIE-4P-368076           VIA51
ZZ.00PAD.MP1       VIA-PCIE-4P-368076           VIA52
ZZ.00PAD.MP1       VIA-PCIE-4P-368076           VIA53
ZZ.00PAD.MP1       VIA-PCIE-4P-368076           VIA54
ZZ.00PAD.MP1       VIA-PCIE-4P-368076           VIA55
ZZ.00PAD.MP1       VIA-PCIE-4P-368076           VIA56
ZZ.00PAD.MP1       VIA-PCIE-4P-368076           VIA57
ZZ.00PAD.MP1       VIA-PCIE-4P-368076           VIA58
ZZ.00PAD.MP1       VIA-PCIE-4P-368076           VIA59
ZZ.00PAD.MP1       VIA-PCIE-4P-368076           VIA60
ZZ.00PAD.MP1       VIA-PCIE-4P-368076           VIA61
ZZ.00PAD.MP1       VIA-PCIE-4P-368076           VIA62
ZZ.00PAD.MP1       VIA-PCIE-4P-368076           VIA63
ZZ.00PAD.MP1       VIA-PCIE-4P-368076           VIA64
ZZ.00PAD.MP1       VIA-PCIE-4P-368076           VIA65
ZZ.00PAD.MP1       VIA-PCIE-4P-368076           VIA66
ZZ.00PAD.MP1       VIA-PCIE-4P-368076           VIA67
82.30004.901       OSC-3225-4P-4H30             X1
82.20043.221       OSC-3225-4P-3H48             X2

EOS

POSITION

C1        3694.00     1177.00       0.000    TOP
C2        3450.34     1256.12     180.000    TOP
C8        3777.14     6247.80     180.000    BOT
C9        3676.20     6013.64     180.000    BOT
C10       3618.00     6017.00     180.000    BOT
C11       3694.80     6242.36       0.000    BOT
C12       3530.00     6126.00      90.000    BOT
C13       3756.00     6014.00     180.000    BOT
C14       3609.80     5886.86       0.000    BOT
C15       3492.00     6349.00     180.000    BOT
C16       3540.00     6349.00     180.000    BOT
C17       3607.86     6398.80     270.000    TOP
C18       3702.20     5835.86       0.000    TOP
C19       3521.80     6392.14     180.000    TOP
C20       3684.14     6398.20      90.000    TOP
C21       3450.34     1151.12       0.000    TOP
C22       3400.34     1151.12       0.000    TOP
C25       3219.05     1915.49     270.000    BOT
C26        737.68      617.55     180.000    TOP
C27       2918.95     5392.94      90.000    TOP
C28       3110.57     1976.74     180.000    BOT
C29       3251.00     2354.00     270.000    BOT
C30       2996.00     5279.00      90.000    BOT
C31        340.00      515.00     180.000    TOP
C32       3178.00     5261.00      90.000    TOP
C33       2437.31     7040.74       0.000    TOP
C34       2630.00     6775.00       0.000    TOP
C35       2671.00     6701.00     180.000    TOP
C36       1808.37     4637.61      90.000    TOP
C37       3300.00     5850.00      90.000    TOP
C38       2613.00     6660.00      90.000    TOP
C39       3275.38     6020.24     180.000    BOT
C40       2852.00     5311.00     270.000    TOP
C41       2865.36     5984.19     270.000    BOT
C44       3205.00     5990.00     270.000    TOP
C49       1885.00     6918.00       0.000    TOP
C50       2580.00     6555.00     180.000    TOP
C51       3873.00     5411.00      90.000    TOP
C52       2764.00     6407.72      90.000    TOP
C53       1737.69     5799.40      90.000    BOT
C54       1411.89     5985.37     180.000    BOT
C55       1737.79     5833.87     270.000    BOT
C56       1783.48     5682.51      90.000    BOT
C57       1354.49     5627.49     180.000    BOT
C58       1512.57     5632.23       0.000    BOT
C59       1465.67     5631.91       0.000    BOT
C60       1418.87     5632.91       0.000    BOT
C61        643.50     5797.00     180.000    BOT
C62        520.50     5802.50     270.000    BOT
C63        503.00     5863.50     270.000    BOT
C64       1026.74     5358.24      90.000    BOT
C65        446.68     5673.16     270.000    BOT
C66        782.47     5642.79     180.000    BOT
C67        928.70     5662.15     180.000    BOT
C68        654.00     5478.00     180.000    BOT
C69        971.13     5661.86     180.000    BOT
C70       1006.19     5661.85     180.000    BOT
C71       1505.16     5703.05     270.000    BOT
C72        962.87     5746.99       0.000    BOT
C73       1019.30     5764.52      90.000    BOT
C74       2701.00     4654.00      90.000    TOP
C75       2977.67     5841.18     180.000    TOP
C76       2941.67     5841.18     180.000    TOP
C78       2826.00     6839.00     180.000    TOP
C79       1193.00     5166.00       0.000    TOP
C80       2530.00     6098.00     270.000    BOT
C81       2495.00     6203.00     180.000    BOT
C82       2567.58     5895.79      90.000    TOP
C83       2890.11     5532.56      90.000    BOT
C84       2099.50     6341.00     270.000    TOP
C85       2100.00     6269.00      90.000    TOP
C86       2087.00     6306.00     270.000    TOP
C87       2451.00     6330.00     180.000    BOT
C88       2503.00     6318.00       0.000    BOT
C89       1256.00     6270.00       0.000    TOP
C90       1319.00     6271.00       0.000    TOP
C91       1360.00     6271.00       0.000    TOP
C92       1291.00     5993.00     180.000    BOT
C93       1336.00     5988.00     180.000    BOT
C94       1371.00     5988.00     180.000    BOT
C95       2478.24     6296.14      90.000    TOP
C96       2487.25     6337.76      90.000    TOP
C97       1534.95     5523.66     180.000    BOT
C98       1972.30     5746.70       0.000    BOT
C99       1488.40     5523.35     180.000    BOT
C100      1925.71     5592.10     270.000    BOT
C101      1998.30     5834.40     270.000    BOT
C102      1273.00     6405.00     180.000    TOP
C103      1231.00     6407.00     180.000    TOP
C104      1440.37     5522.86       0.000    BOT
C105      1194.00     6407.00     180.000    TOP
C106      1378.24     5485.46     180.000    BOT
C107      1892.89     5826.25      90.000    BOT
C108      1815.05     5785.91       0.000    BOT
C109      2080.00     5200.00       0.000    BOT
C110      1980.00     5200.00       0.000    BOT
C113      2030.00     5200.00       0.000    BOT
C114      2180.00     5200.00       0.000    BOT
C115      2130.00     5200.00     180.000    BOT
C116      2282.01     5145.68       0.000    BOT
C117      2135.00     6384.00      90.000    BOT
C118      2154.06     6396.92     180.000    TOP
C120      2282.00     6409.00     180.000    TOP
C122      2079.00     6397.00     180.000    TOP
C123      2238.19     6341.88      90.000    BOT
C125      3366.31     6835.26     180.000    TOP
C126      3676.09     5096.99     270.000    BOT
C127      3892.11     5770.31      90.000    TOP
C128      4532.88      545.22     270.000    TOP
C129      4812.26      557.78      90.000    TOP
C130      4915.00      380.00      90.000    TOP
C131      4443.35      343.57     270.000    TOP
C132      4729.29      258.00      90.000    BOT
C133      4705.86      530.22      90.000    TOP
C134      5233.01      526.49       0.000    TOP
C135      3300.00     5813.94      90.000    TOP
C136      3777.00     7104.00      90.000    TOP
C137      3639.80     5513.90     270.000    BOT
C138      5510.00      612.00      90.000    TOP
C139      5391.08      720.41     180.000    TOP
C141      3843.00     6980.00      90.000    TOP
C144      4935.00      565.00       0.000    BOT
C145      5065.00      565.00       0.000    BOT
C146      5043.81      251.99       0.000    TOP
C147      4360.55      471.44     270.000    TOP
C148      4360.57      424.88     270.000    TOP
C149      4360.46      518.00     270.000    TOP
C150      4464.03      347.00       0.000    BOT
C151      8892.92     2091.35      90.000    TOP
C152      8921.13     2013.50      90.000    TOP
C153      8921.26     2013.29      90.000    BOT
C154      8893.01     2091.31      90.000    BOT
C155      8892.92     2168.35      90.000    TOP
C156      8431.22     1603.14     270.000    TOP
C157      8654.45     2121.85     270.000    BOT
C158      8634.86     1594.90      90.000    BOT
C159      8939.74     1809.35     180.000    TOP
C160      8514.22     1450.14     270.000    TOP
C161      8639.68     2105.64      90.000    TOP
C162      8496.25     1794.77     180.000    TOP
C163      8456.25     1793.77       0.000    TOP
C164      8826.22      727.14       0.000    TOP
C165      8906.22      727.14       0.000    TOP
C166      8986.22      727.14       0.000    TOP
C167      8751.72     1111.38     270.000    TOP
C168      8751.72      906.38     270.000    TOP
C169      2254.00     7148.00       0.000    TOP
C170      1017.49     7345.15     180.000    TOP
C171       940.20     7344.91     180.000    TOP
C172      2196.00     7139.00       0.000    TOP
C173      1248.20     7361.91     180.000    TOP
C174      2118.00     7139.00       0.000    TOP
C175      1979.20     7244.91       0.000    TOP
C176      1094.49     7345.15     180.000    TOP
C177      1171.49     7345.15     180.000    TOP
C178      1609.64     7202.68       0.000    BOT
C179       963.00     7057.00     270.000    BOT
C180      1456.17     7400.48     270.000    TOP
C181      1717.47     7066.75       0.000    TOP
C182      1156.19     7099.95     180.000    TOP
C183      1469.00     6916.00     270.000    TOP
C184      1468.49     6877.15      90.000    TOP
C186      3723.04     1972.91     270.000    TOP
C187      3187.63     2244.90     180.000    BOT
C188      3110.97     2245.15     180.000    BOT
C189      3494.82     1897.78      90.000    TOP
C190      2930.04     6881.20     270.000    TOP
C191      3245.74     6919.70      90.000    TOP
C192      3216.70     7028.74     180.000    TOP
C193      3138.70     7029.74     180.000    TOP
C194      3245.74     6842.70      90.000    TOP
C195      3147.20     6800.20       0.000    TOP
C196      2740.03     7043.37      90.000    TOP
C197      2830.32     7334.36     180.000    TOP
C198      3117.04     7139.20       0.000    TOP
C199      2984.70     7349.74     180.000    TOP
C200      3063.70     7349.74     180.000    TOP
C201      2738.20     7156.20     270.000    TOP
C202      6037.47      649.07     180.000    TOP
C203      6160.47      631.07      90.000    TOP
C204      6170.47      774.07      90.000    TOP
C205      6170.47      693.07      90.000    TOP
C206      5866.47      590.07       0.000    TOP
C207      6317.81      602.11       0.000    TOP
C208      5891.04      414.67       0.000    TOP
C209      5821.04      459.67     270.000    TOP
C210      6225.37      327.26       0.000    TOP
C211      6413.47      602.07     180.000    TOP
C212      5864.47      590.07       0.000    BOT
C213      6062.47      303.07     270.000    TOP
C214      6694.47      359.07       0.000    TOP
C215      6638.47      361.07       0.000    BOT
C216      6638.47      361.07       0.000    TOP
C217      6558.47      361.07       0.000    TOP
C218      6558.47      361.07       0.000    BOT
C219      3606.82     1851.74     270.000    TOP
C222       630.84     6439.00     270.000    TOP
C223       837.50     6584.54     180.000    TOP
C224       915.50     6583.54     180.000    TOP
C225       946.54     6391.50      90.000    TOP
C226       946.54     6470.50      90.000    TOP
C227       854.00     6367.16       0.000    TOP
C228       432.52     6599.09      90.000    TOP
C229       734.27     6927.85     180.000    TOP
C230       817.84     6697.00       0.000    TOP
C231       907.83     6820.24      90.000    TOP
C232       907.83     6741.24      90.000    TOP
C233       464.84     6718.00     270.000    TOP
C234      3038.70     6123.50     270.000    TOP
C235      3246.36     6314.04     180.000    TOP
C236      3265.40     6115.00      90.000    TOP
C237      3324.36     6313.04     180.000    TOP
C238      3265.40     6194.00      90.000    TOP
C239      3176.00     6086.00       0.000    TOP
C240      2831.70     6372.50      90.000    TOP
C241      2940.18     6627.82     180.000    TOP
C242      3220.00     6438.00       0.000    TOP
C243      3171.36     6622.04     180.000    TOP
C244      3092.36     6622.04     180.000    TOP
C245      2843.70     6441.50     270.000    TOP
C246      3677.00     1489.00     180.000    TOP
C485      3299.23     5799.49      90.000    BOT
C502      3087.00     5137.00       0.000    BOT
C503      3546.62     5212.46       0.000    BOT
C504      3576.89     5401.88     270.000    BOT
C505      2076.00     4973.80     180.000    BOT
C506      2180.00     4673.00      90.000    BOT
C507      3706.50     1918.14     180.000    TOP
C508      1256.00     5046.00     270.000    BOT
C511      3218.29     1836.98     270.000    BOT
C512      3294.35     2218.84       0.000    BOT
C513      2866.95     5764.63     270.000    TOP
C518      2588.23     6263.46       0.000    TOP
C519      1438.23     6138.46       0.000    BOT
C520      2186.23     6538.46       0.000    TOP
C522      3646.00     4937.00     180.000    TOP
C524      3031.00     6598.30     180.000    TOP
C525      3750.00      245.00      90.000    BOT
C528       962.68      622.55     270.000    TOP
C529       565.00      520.00     270.000    TOP
C601      7059.00     4238.00     270.000    TOP
C602      7888.00     4228.00     270.000    TOP
C605      7654.53     5269.25     180.000    BOT
C606      8002.91     5132.68     180.000    BOT
C607      7906.67     5133.52     180.000    BOT
C608      7866.67     5133.52     180.000    BOT
C609      7826.67     5133.52     180.000    BOT
C610      7498.75     5268.96     180.000    BOT
C612      7603.75     5268.96     180.000    BOT
C613      7563.75     5268.96     180.000    BOT
C614      6993.65     5144.53     180.000    BOT
C615      6864.96     5146.47     180.000    BOT
C616      6901.34     5146.96     180.000    BOT
C617      6774.47     4747.27       0.000    BOT
C618      6694.32     4867.02     270.000    BOT
C619      6694.32     4907.02     270.000    BOT
C620      6694.32     4942.02     270.000    BOT
C621      6890.00     4906.09      90.000    BOT
C623      6888.00     4965.09      90.000    BOT
C624      6888.00     5002.09      90.000    BOT
C625      7792.39     5260.60     180.000    BOT
C626      7694.53     5269.25     180.000    BOT
C627      2057.00     6344.00     270.000    BOT
C628      7734.53     5269.25     180.000    BOT
C629      7946.67     5133.52     180.000    BOT
C630      6936.92     5146.62     180.000    BOT
C631      8068.25     4224.15       0.000    BOT
C632      8153.34     3918.62       0.000    BOT
C633      6898.75     4706.36     180.000    BOT
C634      7000.25     4459.86      90.000    BOT
C635      8821.14     3982.88     270.000    BOT
C636      8994.91     4022.39     180.000    TOP
C637      9016.90     4014.44     180.000    BOT
C638      8940.72     4014.25     180.000    BOT
C639      8857.86     2697.45      90.000    BOT
C640      8857.86     2997.45      90.000    BOT
C641      6694.32     4826.02     270.000    BOT
C643      8857.86     3077.45      90.000    BOT
C644      8429.84     3727.69     180.000    TOP
C645      8603.20     4056.72      90.000    TOP
C646      8906.39     3693.60     180.000    TOP
C647      8665.41     3963.86     180.000    BOT
C648      8389.72     3727.69       0.000    TOP
C650      8857.86     2917.45      90.000    BOT
C652      8475.06     3402.40     270.000    TOP
C653      8632.98     3487.15      90.000    BOT
C655      8857.86     2837.45      90.000    BOT
C657      8857.01     3037.08      90.000    TOP
C658      8857.01     2832.08      90.000    TOP
C659      8784.39     4027.23     180.000    TOP
C660      8857.86     2757.45      90.000    BOT
C670      8488.20     3665.72      90.000    TOP
C671      8841.02     4022.56     180.000    TOP
C672      8917.94     4022.41     180.000    TOP
C998       890.00     6773.00      90.000    BOT
C999       875.00     6814.00      90.000    BOT
CA1       4773.43      374.19     180.000    BOT
CN1       5562.99     1740.16     180.000    TOP
D1        5309.98      714.31       0.000    TOP
D2         827.68      617.55       0.000    TOP
D3         430.00      515.00       0.000    TOP
D4        3582.05     2335.65      90.000    TOP
D11       2776.00     6701.00       0.000    TOP
D13       3522.37     1042.00      90.000    TOP
D14       3742.70      482.00      90.000    TOP
D15       3742.70      528.00      90.000    TOP
D16       3739.70      817.00      90.000    TOP
D17       3739.70      863.00      90.000    TOP
D18       3720.00      639.00     180.000    TOP
D19       3720.00      703.00       0.000    TOP
G1        9042.62      715.15     270.000    TOP
G2        8502.68     1925.64      90.000    TOP
G3        1347.00     6961.00     180.000    TOP
G4        6736.47      359.07     270.000    TOP
G5        5886.47      338.07       0.000    TOP
G10       8519.17     3831.81      90.000    BOT
L1        3894.58      724.49      90.000    TOP
L2        2418.00     6202.00     180.000    BOT
L3        1226.00     5986.00       0.000    BOT
L4        2471.24     6231.14     270.000    TOP
L5        1336.00     6415.00       0.000    TOP
L6        8853.59     2200.15       0.000    BOT
L7        8826.22     1468.14       0.000    TOP
L8         917.00     7227.00      90.000    TOP
L9        1692.47     7287.75      90.000    TOP
L10       6381.47      427.07      90.000    TOP
L23       3335.00     1150.00     180.000    TOP
L30       8995.97     3881.57     180.000    TOP
L31       8774.56     3397.01       0.000    TOP
LED3      8110.24      244.09       0.000    TOP
LED6       936.14     5043.52     180.000    TOP
M1        8047.24     5102.36       0.000    TOP
M2        7062.99     5102.36       0.000    TOP
MEZZ1     3059.06     2856.30     270.000    TOP
NUT1      1631.89     6692.91       0.000    TOP
OSC1      1304.00     5178.00       0.000    TOP
P1        4930.35      474.57     270.000    TOP
PQ1       4929.28      611.51     270.000    TOP
PQ2       3652.59     1758.44      90.000    TOP
PQ3       3491.11     2099.68       0.000    TOP
PU1       8696.22     1912.65     180.000    TOP
PU2       1350.19     7148.45     270.000    TOP
PU4       6060.04      449.67      90.000    TOP
PU9       2956.34     7100.70     270.000    TOP
PU10       657.14     6658.50     270.000    TOP
PU11      3063.00     6386.00     270.000    TOP
PWR1       944.88      344.49       0.000    TOP
Q2        2722.06     6537.33     270.000    TOP
Q3        2485.00     6525.00      90.000    TOP
Q4        2485.00     6665.00      90.000    TOP
Q5        5310.93      316.33     270.000    TOP
Q11       3286.00     6621.00       0.000    TOP
Q12       3431.00     6625.00     270.000    TOP
Q20       8241.16     3307.94       0.000    BOT
Q21       8245.16     3502.14     270.000    BOT
Q24       5221.50      681.40       0.000    BOT
Q25       3406.31     3885.74     180.000    BOT
Q26       3672.00     5635.00     270.000    BOT
Q27       7726.00      275.00       0.000    TOP
Q28       7143.00      269.00     270.000    TOP
R3        3420.48     2280.17     270.000    TOP
R4        3420.18     2321.81      90.000    TOP
R5        3496.62     2421.93     270.000    TOP
R7        3496.61     2470.04     270.000    TOP
R8        3496.61     2510.04     270.000    TOP
R9        3497.82     2577.78      90.000    TOP
R10       3497.82     1786.78      90.000    TOP
R14       3461.82     2657.78     270.000    TOP
R15       3478.82     2727.78       0.000    TOP
R16       3435.82     1801.78       0.000    TOP
R18       3895.36     6179.80     270.000    TOP
R19       3913.00     6054.00     270.000    TOP
R20       3909.36     6285.80     270.000    TOP
R21       3734.00     6243.00       0.000    BOT
R22       3776.15     6174.25     270.000    BOT
R23       3895.00     6139.00      90.000    TOP
R24       3566.80     5873.64     180.000    TOP
R25       3611.20     5873.86       0.000    TOP
R26       3908.81     6222.65      90.000    TOP
R27       3643.64     6359.20      90.000    TOP
R28       3476.80     6379.64     180.000    TOP
R29       3830.00     5821.00     180.000    TOP
R30       3912.00     5891.00     270.000    TOP
R31       3913.00     6013.00     270.000    TOP
R32       3909.00     6379.00     270.000    TOP
R33       3524.80     5858.64     180.000    TOP
R34       3788.00     5821.00     180.000    TOP
R35       3912.36     5850.80     270.000    TOP
R36       3912.00     5932.00     270.000    TOP
R37       3755.00      310.00      90.000    BOT
R38       3914.58      724.49     180.000    TOP
R39       3200.00     5355.00     180.000    TOP
R40       3570.00     5885.00       0.000    BOT
R41       3746.00     5851.00       0.000    TOP
R42       3800.00     6001.00     180.000    BOT
R43       3913.00     5972.00      90.000    TOP
R45        967.68      552.55     270.000    TOP
R46       3874.58      724.49     180.000    TOP
R47        570.00      450.00     270.000    TOP
R48        782.68      617.55       0.000    TOP
R49       2741.25     5411.21      90.000    TOP
R50       2882.86     5855.55       0.000    BOT
R51       2910.55     5467.06     270.000    TOP
R52       2827.45     5616.94      90.000    TOP
R53       2882.86     5780.20     180.000    BOT
R56       2657.00     5531.00      90.000    TOP
R58       2913.00     5513.00     270.000    TOP
R59       2675.14     5422.85       0.000    TOP
R64       3298.00     3877.74     270.000    BOT
R65        385.00      515.00       0.000    TOP
R71       2508.00     6776.00     180.000    TOP
R72       2580.00     6479.64     180.000    TOP
R73       2764.00     6445.72     270.000    TOP
R74       2467.00     6776.00       0.000    TOP
R75       2388.07     6568.71     180.000    TOP
R76       2585.82     6421.99     270.000    TOP
R77       2371.89     6626.67      90.000    TOP
R78       2585.00     6775.00     180.000    TOP
R79       2649.88     6664.67     270.000    BOT
R80       2612.76     6697.31      90.000    TOP
R81       2584.31     7065.24       0.000    TOP
R82       2626.45     7065.35     180.000    TOP
R83       1807.63     4698.80     270.000    TOP
R84       1085.00     4805.00     180.000    TOP
R85       1040.00     4805.00       0.000    TOP
R86       1807.63     4597.80     270.000    TOP
R87       2016.00     5033.00      90.000    TOP
R88       1914.00     5041.00     180.000    TOP
R89       1745.88     4914.13       0.000    TOP
R90       1437.00     4738.00     180.000    BOT
R91       1480.00     4738.00     180.000    BOT
R92       3463.66     5947.59      90.000    TOP
R93       3425.00     5855.00      90.000    TOP
R95       3245.00     5355.00     180.000    TOP
R96       3515.00     5857.90       0.000    BOT
R97       3441.02     5929.63     180.000    BOT
R98       2853.00     5350.00      90.000    TOP
R99       2853.00     5228.00      90.000    TOP
R100      3163.22     6062.83      90.000    BOT
R101      3097.65     6020.00     180.000    BOT
R102      3255.00     5260.00     270.000    TOP
R105      2852.00     5273.00      90.000    TOP
R123      3870.00     6798.00     270.000    TOP
R124      3871.00     6839.00     270.000    TOP
R127      3262.85     5661.98     270.000    BOT
R128      3224.25     5580.73     270.000    BOT
R129      3342.53     5768.49     270.000    TOP
R130      3364.99     5727.21     270.000    TOP
R131      3364.55     5679.22     270.000    TOP
R132      3364.95     5637.88     270.000    TOP
R133      3451.00     5379.00     180.000    TOP
R134      3412.26     5302.09       0.000    TOP
R135      3424.97     5223.61     180.000    TOP
R136      3468.00     5438.00      90.000    TOP
R137      3504.00     5302.00       0.000    TOP
R138      3468.19     5223.75       0.000    TOP
R139      3875.00     5334.00      90.000    TOP
R140      1855.38     5361.01      90.000    BOT
R141      1741.02     5740.58     270.000    BOT
R142      1916.94     5343.28       0.000    BOT
R143      1737.87     5871.47      90.000    BOT
R144       866.59     5157.77     180.000    TOP
R145      1565.01     5625.67     180.000    BOT
R146      2175.00     5120.66     270.000    TOP
R147      2126.00     5187.00       0.000    TOP
R148      2035.00     5186.00       0.000    TOP
R149      1987.00     5186.00       0.000    TOP
R151      2412.20     5625.21      90.000    BOT
R152      1836.70     5300.66     180.000    BOT
R153      2431.30     5667.32      90.000    BOT
R154      1794.00     5301.00     180.000    BOT
R155      2412.96     5644.98      90.000    TOP
R156      1865.00     4890.00     270.000    BOT
R157      2412.96     5603.98      90.000    TOP
R158      1784.69     5196.93     180.000    TOP
R159      2697.09     5621.13     180.000    BOT
R160      2403.25     5685.22     270.000    TOP
R161      2698.06     5696.52       0.000    BOT
R162      2428.42     5725.85     270.000    TOP
R163      2426.00     5768.00       0.000    BOT
R164      2419.00     5857.00     270.000    TOP
R165      2434.30     5710.32      90.000    BOT
R166      2405.58     5816.90     270.000    TOP
R167      2072.78     5341.01       0.000    BOT
R168      1932.85     6244.00       0.000    TOP
R169      2194.73     5338.73       0.000    BOT
R170      1891.85     6244.00       0.000    TOP
R171      1850.85     6244.00       0.000    TOP
R172      1809.85     6244.00       0.000    TOP
R173      1768.00     6244.00       0.000    TOP
R174      1727.00     6244.00       0.000    TOP
R175      2397.00     5519.00     270.000    BOT
R176      2397.00     5561.00     270.000    BOT
R177      1906.00     5177.00     180.000    TOP
R178      1946.49     5186.51     180.000    TOP
R179      1828.76     6347.68     180.000    TOP
R180      1787.76     6347.68     180.000    TOP
R181      2524.25     5672.60      90.000    TOP
R182      2503.00     5735.00      90.000    TOP
R183      1859.80     5200.45      90.000    BOT
R184      1732.00     5267.00     270.000    BOT
R185      2431.00     5437.00     270.000    BOT
R186      2507.00     5436.00      90.000    BOT
R187      1747.00     6355.00     180.000    TOP
R188      1706.00     6355.00     180.000    TOP
R189      2494.00     5857.00      90.000    TOP
R190      2504.00     5783.00      90.000    TOP
R191      1974.00     6428.00      90.000    BOT
R192      1895.45     6426.81      90.000    BOT
R193      2738.09     5621.11     180.000    BOT
R194      2738.95     5696.52       0.000    BOT
R195      2469.80     5602.68       0.000    BOT
R196      2512.00     5671.00      90.000    BOT
R197      2259.84     6607.43       0.000    TOP
R198      2497.77     5630.68      90.000    TOP
R199      2496.96     5570.61      90.000    TOP
R200      1871.67     5046.84       0.000    TOP
R201      2523.00     5790.00     180.000    BOT
R202      2512.00     5711.00      90.000    BOT
R203      1910.76     6348.98     180.000    TOP
R204      1869.76     6347.68     180.000    TOP
R205       802.24     5583.98     270.000    BOT
R206       802.25     5543.63     270.000    BOT
R207       349.58     5382.54      90.000    TOP
R208       425.06     5382.49      90.000    TOP
R209       524.56     5717.95      90.000    BOT
R210       568.00     5758.50      90.000    BOT
R211       401.00     5609.00      90.000    BOT
R212       476.85     5608.79      90.000    BOT
R213       866.73     5083.00     180.000    TOP
R214       920.00     5157.00     180.000    TOP
R215       753.73     5081.79     180.000    TOP
R216       754.05     5157.77     180.000    TOP
R217       348.00     5495.00      90.000    TOP
R218       423.00     5495.00      90.000    TOP
R219      1082.77     5723.51       0.000    TOP
R220       699.00     5083.00     180.000    TOP
R221       697.78     5157.77     180.000    TOP
R222       997.76     5601.66     270.000    BOT
R223       997.44     5552.40     270.000    BOT
R224       424.06     5326.22      90.000    TOP
R225       810.68     5081.66     180.000    TOP
R226       810.32     5157.77     180.000    TOP
R227       349.87     5551.53      90.000    TOP
R228       424.87     5551.53      90.000    TOP
R229       350.58     5438.81      90.000    TOP
R230       425.06     5438.76      90.000    TOP
R231      1011.00     5136.00     180.000    TOP
R232      1011.13     5210.77     180.000    TOP
R233       402.03     5495.08      90.000    BOT
R234       476.85     5495.26      90.000    BOT
R235       753.73     5081.79     180.000    BOT
R236       754.05     5157.77     180.000    BOT
R237       401.32     5212.71      90.000    BOT
R238       476.06     5212.69      90.000    BOT
R239       349.65     5326.38     270.000    TOP
R240       698.78     5080.77     180.000    BOT
R241       697.78     5157.77     180.000    BOT
R242       401.75     5269.95      90.000    BOT
R243       476.06     5269.95      90.000    BOT
R244       979.00     5083.00     180.000    BOT
R245       979.13     5157.77     180.000    BOT
R246       401.58     5438.81      90.000    BOT
R247       476.06     5438.76      90.000    BOT
R248       922.73     5083.00     180.000    BOT
R249       922.86     5157.77     180.000    BOT
R250       400.58     5382.54      90.000    BOT
R251       476.06     5382.49      90.000    BOT
R252       810.68     5081.66     180.000    BOT
R253       810.32     5157.77     180.000    BOT
R254       401.85     5551.53      90.000    BOT
R255       476.85     5551.53      90.000    BOT
R256       401.65     5326.38      90.000    BOT
R257       476.06     5326.22      90.000    BOT
R258       642.51     5081.77     180.000    BOT
R259       641.51     5157.77     180.000    BOT
R260       866.73     5083.00     180.000    BOT
R261       866.59     5157.77     180.000    BOT
R262      1703.80     5187.00     180.000    TOP
R263      1662.80     5187.00     180.000    TOP
R264      1824.74     5189.91     180.000    TOP
R265      1865.37     5176.81     180.000    TOP
R266      2697.00     4703.00     270.000    TOP
R267      2701.00     4895.00     270.000    TOP
R268      2697.00     4582.00     270.000    TOP
R269      2104.00     4953.00      90.000    TOP
R270      1708.00     5048.00       0.000    BOT
R271      2437.00     5538.00       0.000    TOP
R272      2373.00     5454.00       0.000    BOT
R273      2333.00     5454.00       0.000    BOT
R274      1826.48     5047.54       0.000    TOP
R275      3639.80     5442.00     270.000    BOT
R276      3843.00     5501.00       0.000    TOP
R277      1467.00     5284.00     180.000    BOT
R278      2293.42     5166.55       0.000    TOP
R279      1958.70     6362.10      90.000    BOT
R280      1386.00     5297.00      90.000    TOP
R281      1884.04     6361.90      90.000    BOT
R282      2121.18     4692.93     180.000    BOT
R283      1287.00     5346.00      90.000    TOP
R284      1670.00     5188.00     180.000    BOT
R285      2221.00     4769.00       0.000    BOT
R286      1923.00     4918.00     180.000    BOT
R287      1955.00     5045.00     180.000    TOP
R288      2252.62     5168.80     180.000    TOP
R289      2373.00     5205.63     270.000    TOP
R290      2374.09     5247.00     270.000    TOP
R291      1960.13     5344.75     180.000    BOT
R292      1790.00     5048.00       0.000    BOT
R293      1763.86     5131.71      90.000    BOT
R294      2005.46     5015.09     270.000    BOT
R295      2280.57     5345.56     270.000    BOT
R296      1849.24     4914.48     180.000    TOP
R297      1947.18     6242.94     180.000    BOT
R298      1965.00     6096.00     180.000    BOT
R299      1508.72     6354.32       0.000    TOP
R300      1425.72     6354.32       0.000    TOP
R301      3075.17     6829.59     270.000    BOT
R302      3078.49     6672.00     180.000    BOT
R303      2259.00     6099.00       0.000    BOT
R304      2218.00     6100.00       0.000    BOT
R305      2867.03     6167.11     180.000    TOP
R306      2694.00     6058.00     270.000    TOP
R307      2980.15     5928.31      90.000    TOP
R308      1420.00     5138.00     180.000    TOP
R309      1574.58     6355.32       0.000    TOP
R310      1884.31     6116.38       0.000    BOT
R311      1844.00     6096.00     180.000    BOT
R312      1419.14     5215.38       0.000    TOP
R313      1665.00     6355.00       0.000    TOP
R314      1625.37     5038.54       0.000    BOT
R315      2125.00     6102.00     180.000    BOT
R316      1553.41     6148.72     180.000    BOT
R317      1494.00     6249.00       0.000    TOP
R318      1475.00     5967.00     270.000    BOT
R319      1329.62     6033.11     270.000    TOP
R320      1339.95     6173.54     270.000    TOP
R321      1512.57     6025.62     270.000    BOT
R322      1349.77     6130.60     270.000    TOP
R323      1924.71     6126.38       0.000    BOT
R324      1864.10     6176.88      90.000    BOT
R325      1667.37     5038.54       0.000    BOT
R326      1614.00     6199.00     270.000    BOT
R327      3148.00     6797.00       0.000    BOT
R328      1537.00     6245.00     180.000    TOP
R329      3365.04     5595.44     270.000    TOP
R330      3061.00     6613.00      90.000    BOT
R331      1201.03     6138.18      90.000    TOP
R332      2712.00     6744.00     180.000    TOP
R333      1359.49     5990.62     270.000    TOP
R334      2670.00     5845.00     270.000    BOT
R335      2439.00     6151.00       0.000    TOP
R336      1265.00     6105.00      90.000    BOT
R337      2180.00     4711.00      90.000    BOT
R338      2420.00     5898.00      90.000    TOP
R339      2179.08     4813.35       0.000    BOT
R340      2416.00     6010.00      90.000    TOP
R341      2011.00     4830.00     270.000    BOT
R342      1698.01     4691.68     270.000    BOT
R343      2449.38     5285.01     270.000    TOP
R344      1698.01     4732.68     270.000    BOT
R345      2267.25     4841.51      90.000    BOT
R346       935.31     4946.41     180.000    TOP
R347      2121.65     4847.08       0.000    BOT
R348      1582.94     5038.54       0.000    BOT
R349      3348.27     5188.53       0.000    TOP
R350      1525.89     4877.81     180.000    BOT
R351      1387.67     5377.95      90.000    TOP
R352      2471.28     5366.60     270.000    TOP
R353      2154.48     5339.01     180.000    BOT
R354      2395.63     5391.42     270.000    TOP
R355      2113.78     5341.01       0.000    BOT
R356      2475.00     7040.00       0.000    TOP
R357      2009.10     5614.90     180.000    BOT
R358      2297.00     5670.00     270.000    BOT
R359      2260.00     5859.00     270.000    BOT
R360      2260.75     5768.16     270.000    BOT
R361      2257.00     5719.00     270.000    BOT
R362      1627.00     4940.00     180.000    BOT
R363      1968.90     5656.00     180.000    BOT
R364      1667.61     4940.20       0.000    BOT
R365      2258.48     5816.66      90.000    BOT
R366      2023.00     6088.00     270.000    BOT
R367      1898.28     6439.63      90.000    TOP
R368      1196.00     6271.00     180.000    TOP
R369      1287.00     5303.00      90.000    TOP
R370      1585.89     5208.12      90.000    BOT
R371      1749.00     5048.00     180.000    BOT
R372      1732.00     5307.00      90.000    BOT
R373      1633.00     5289.00     180.000    BOT
R374      1674.54     5291.77     180.000    BOT
R375      1586.00     5267.00     180.000    BOT
R376      1619.02     5176.49     180.000    TOP
R377      1479.92     5156.86      90.000    TOP
R378      1578.96     5176.19     180.000    TOP
R379      1479.92     5196.86      90.000    TOP
R380      2966.80     5545.64     180.000    BOT
R381      2729.00     5860.00       0.000    BOT
R382      2519.00     6151.00       0.000    TOP
R383      2247.00     5972.00     270.000    BOT
R384      2381.00     5847.00     180.000    BOT
R385      2948.20     5611.23      90.000    BOT
R386      2670.00     5885.00      90.000    BOT
R387      2479.00     6151.00     180.000    TOP
R388      2247.00     5932.00     270.000    BOT
R389      2421.00     5847.00     180.000    BOT
R390      2259.00     6254.00       0.000    TOP
R391      2299.52     6281.30       0.000    TOP
R392      2344.00     6343.00      90.000    TOP
R393      2372.00     5975.00      90.000    BOT
R394      2298.92     6228.02     270.000    BOT
R395      2219.00     6254.00       0.000    TOP
R396      2340.00     6235.00       0.000    TOP
R397      2380.00     6235.00       0.000    TOP
R398      2372.00     5935.00     270.000    BOT
R399      2240.00     6210.00     180.000    BOT
R400      2004.55     6258.14     270.000    BOT
R401      2134.00     6422.00     270.000    BOT
R402      2234.00     6397.00       0.000    TOP
R403      2048.00     4888.00       0.000    BOT
R404      2135.00     6345.00      90.000    BOT
R405      2192.00     6405.00     180.000    TOP
R406      1985.00     4895.00      90.000    BOT
R407      2360.00     6409.00       0.000    TOP
R408      3046.17     5915.81       0.000    TOP
R409      2041.00     6397.00       0.000    TOP
R410      2320.00     6409.00     180.000    TOP
R411      7238.00      314.00     180.000    TOP
R412      2117.06     6396.92     180.000    TOP
R413      2237.92     6420.06     270.000    BOT
R415      2238.08     6378.94      90.000    BOT
R416      1466.00     5190.00     180.000    BOT
R417      3576.55     6794.45     180.000    BOT
R418      3592.33     6736.96      90.000    BOT
R419      3591.35     6615.05     270.000    BOT
R420      3495.61     5078.31      90.000    TOP
R421      3495.00     5119.00     270.000    TOP
R422      3460.00     5810.00     270.000    TOP
R423      3884.89     5542.35     180.000    TOP
R424      3459.00     5749.00      90.000    BOT
R425      3640.00     5749.00      90.000    BOT
R426      3899.44     5729.99     270.000    TOP
R427      3898.95     5684.31     270.000    TOP
R428      3881.00     5644.00      90.000    TOP
R429      3459.00     5792.31     270.000    BOT
R430      3698.00     5763.00     180.000    BOT
R431      4643.42      555.58       0.000    TOP
R432      4812.26      595.62      90.000    TOP
R433      4919.50      337.81     270.000    BOT
R434      4875.14      518.41      90.000    TOP
R435      4919.00      340.00      90.000    TOP
R436      4599.60      259.90      90.000    BOT
R437      4955.18      426.07     270.000    BOT
R438      4915.00      300.00     270.000    TOP
R439      4915.00      420.00      90.000    TOP
R440      4684.00      630.00       0.000    TOP
R441      4727.00      629.00       0.000    TOP
R442      5293.00      546.48     270.000    TOP
R443      5292.97      501.48     270.000    TOP
R444      5422.45      511.48     180.000    TOP
R445      4935.00      656.00       0.000    BOT
R446      5090.00      650.00     270.000    BOT
R447      4981.50      570.30       0.000    BOT
R448      5115.00      565.00       0.000    BOT
R449      4919.60      378.83      90.000    BOT
R450      5187.72      266.80     270.000    TOP
R451      3231.75     6784.43     270.000    TOP
R452      3120.00     6650.00     180.000    BOT
R453      4434.89      441.01       0.000    TOP
R454      4358.85      380.57     270.000    TOP
R455      5090.55      252.02       0.000    TOP
R456      4442.85      219.57     270.000    TOP
R457      4434.57      517.15     180.000    TOP
R458      4375.58      561.53     270.000    TOP
R459      4443.85      304.57     270.000    TOP
R460      4443.85      261.57     270.000    TOP
R461      4397.00      378.00      90.000    BOT
R462      4443.16      381.47     270.000    TOP
R463      8483.11     1651.78      90.000    TOP
R464      8737.90     2225.73     270.000    BOT
R465      8483.11     1694.78     270.000    TOP
R466      8605.04     1710.44       0.000    BOT
R467      8586.22     1608.14     180.000    TOP
R468      8529.22     1495.14     270.000    TOP
R469      8909.84     1928.00     270.000    TOP
R470      8506.68     2159.64     270.000    TOP
R471      8545.96     1608.35       0.000    TOP
R472      8506.68     2118.64      90.000    TOP
R473      8325.72     1746.77     180.000    TOP
R474      8416.25     1794.77       0.000    TOP
R475      8506.68     2078.64      90.000    TOP
R476      8653.30     2152.62     270.000    TOP
R477      8506.68     2038.64     270.000    TOP
R478      8421.68     1869.14     180.000    TOP
R479      2376.99     7379.47     270.000    TOP
R480      2376.99     7283.47     270.000    TOP
R481      2376.99     7187.47     270.000    TOP
R482      1558.49     6974.15     180.000    TOP
R483       997.00     7122.00     270.000    BOT
R484      1497.00     7192.00     180.000    BOT
R485      1642.49     6974.15       0.000    TOP
R486      1517.49     6974.15       0.000    TOP
R487      1583.49     7052.15     180.000    TOP
R488      1680.47     7067.75       0.000    TOP
R489      1719.49     6918.15     270.000    TOP
R490      1326.51     7362.15       0.000    TOP
R491      1543.00     7052.15       0.000    TOP
R492      1115.99     7014.65     270.000    TOP
R493      1133.49     6953.47     180.000    TOP
R494      1173.49     6953.47     180.000    TOP
R495      1112.00     7116.00       0.000    TOP
R496      1468.49     6837.15      90.000    TOP
R497      1214.49     6925.47     180.000    TOP
R498      1568.49     7112.15      90.000    TOP
R499      1393.49     6877.15     270.000    TOP
R500      3748.83     1828.53       0.000    TOP
R501      1488.03     5093.89      90.000    BOT
R502      3689.80     2455.08      90.000    TOP
R503      3603.82     1919.00     180.000    TOP
R504      3091.00     6790.00     180.000    TOP
R505      2930.18     6841.53     270.000    TOP
R506      2930.82     6919.47      90.000    TOP
R507      2917.00     7319.00       0.000    TOP
R508      2876.20     7319.20       0.000    TOP
R509      2737.20     7194.20      90.000    TOP
R510      2736.90     7235.70     270.000    TOP
R511      5989.47      662.07     180.000    TOP
R512      6003.47      770.07     270.000    TOP
R513      5877.20      504.35      90.000    TOP
R514      5774.04      577.67     180.000    TOP
R515      5903.47      590.07       0.000    TOP
R516      5945.04      589.67     180.000    TOP
R517      6202.96      551.38     270.000    TOP
R518      5836.04      414.67     270.000    TOP
R519      6366.47      586.07     180.000    TOP
R520      6130.57      239.71     270.000    TOP
R521      5810.47      372.07     270.000    TOP
R522      5945.41      312.81       0.000    TOP
R523      3494.82     1935.78      90.000    TOP
R524      4596.10      353.40       0.000    BOT
R525      1744.00     5144.00     180.000    TOP
R526      8191.00     3919.00     180.000    BOT
R527      7000.00     4421.00     270.000    BOT
R528      7033.00      235.00       0.000    TOP
R529       790.50     6337.46     180.000    TOP
R530       631.54     6399.50     270.000    TOP
R531       630.46     6478.50      90.000    TOP
R532       860.28     6914.39       0.000    TOP
R533       819.28     6915.39       0.000    TOP
R534       482.00     6772.84       0.000    TOP
R535       414.54     6797.50     270.000    TOP
R536      3119.36     6052.96     180.000    TOP
R537      3037.00     6163.84     270.000    TOP
R538      3047.53     6205.50      90.000    TOP
R539      2990.00     6598.00       0.000    TOP
R540      2896.12     6632.29       0.000    TOP
R541      2843.70     6479.78      90.000    TOP
R542      2843.70     6520.44      90.000    TOP
R544      8040.00     4361.00     180.000    TOP
R545      7120.00     4371.00       0.000    TOP
R546      7252.00     4371.00       0.000    TOP
R547      7355.00     4310.00     270.000    TOP
R548      7949.00     4361.00       0.000    TOP
R549      8081.00     4361.00       0.000    TOP
R550      8184.00     4258.00      90.000    TOP
R551      7161.00     4371.00     180.000    TOP
R552      7211.00     4371.00     180.000    TOP
R553      7355.00     4268.00      90.000    TOP
R554      8184.00     4300.00     270.000    TOP
R555      7990.00     4361.00     180.000    TOP
R556      7132.00     3925.00       0.000    TOP
R557      7183.00     3925.00       0.000    TOP
R558      7961.00     3915.00       0.000    TOP
R559      8012.00     3915.00       0.000    TOP
R599      1954.00     5285.00      90.000    BOT
R601      2575.61     5483.08     270.000    BOT
R607      2000.31     5344.94       0.000    BOT
R610      2120.00     5010.00     180.000    TOP
R617      3365.64     5554.73     270.000    TOP
R651      3217.83     6744.07     270.000    TOP
R695      7238.00      237.00     180.000    TOP
R697      1777.34     6191.20     270.000    BOT
R698      1281.00     6349.00      90.000    BOT
R699      1279.00     6263.00     270.000    BOT
R700      1493.00     6202.00     270.000    BOT
R701      1250.00     5990.00      90.000    TOP
R702      2185.00     4890.00     180.000    BOT
R703      1281.00     6390.00      90.000    BOT
R705      1281.00     6308.00      90.000    BOT
R706      1415.00     6202.00     270.000    BOT
R707      1847.00     5893.00     180.000    BOT
R708      2314.00     5053.00     270.000    BOT
R709      5076.65      344.32      90.000    TOP
R710      5076.54      420.93     270.000    TOP
R711      4915.00      260.00     270.000    TOP
R712      4914.00      218.00     270.000    TOP
R713      8460.77     1539.24       0.000    TOP
R714      1452.79     6208.70       0.000    TOP
R715      3495.00     5002.00     270.000    TOP
R716      1202.73     4990.59     180.000    BOT
R717      3129.44     5822.63      90.000    TOP
R718      3306.00     5076.00       0.000    BOT
R719      3689.80     2413.08      90.000    TOP
R720      3264.56     5712.67     270.000    BOT
R721      3581.20     5459.04     180.000    BOT
R722      3575.00     5652.00     180.000    BOT
R723      3364.23     6774.72     270.000    TOP
R724      3870.00     6756.00     270.000    TOP
R725      3594.81     4861.66       0.000    TOP
R726      3439.00     6720.00      90.000    TOP
R727      3641.81     2258.61      90.000    TOP
R728      3439.00     3778.00     270.000    BOT
R729      2493.00     5362.00     270.000    BOT
R731      2589.69     5432.21     180.000    TOP
R732      1513.51     5034.97       0.000    BOT
R734      1472.47     5034.87       0.000    BOT
R736      3878.02     6942.23     270.000    TOP
R737      7841.00      250.00      90.000    TOP
R740      1500.00     5905.00      90.000    BOT
R742      5367.06      687.42     270.000    BOT
R743      5195.90      777.00      90.000    BOT
R744      5213.30      838.80     180.000    BOT
R763      2704.19     5744.62      90.000    TOP
R764      2697.00     4743.80      90.000    TOP
R765      1807.39     4740.31      90.000    TOP
R766      2552.60     5935.75     270.000    TOP
R767      1387.00     4839.00      90.000    BOT
R768      1159.71     5964.54     270.000    TOP
R769      1079.49     5997.64     270.000    TOP
R770      1079.49     6079.64     270.000    TOP
R771      1079.49     6038.64     270.000    TOP
R772      1079.49     6120.64     270.000    TOP
R773      1079.49     6243.64     270.000    TOP
R774      2675.00     6395.00     270.000    TOP
R775      2628.23     6263.96       0.000    TOP
R776      1336.00     6160.00       0.000    BOT
R777      1477.23     6138.96       0.000    BOT
R778      2101.23     6572.96       0.000    TOP
R779      2147.23     6537.96       0.000    TOP
R780      1387.00     4797.00      90.000    BOT
R781      1040.00     4890.00       0.000    TOP
R782      1216.43     6163.27     180.000    BOT
R783      1144.72     4973.05      90.000    BOT
R784      2177.53     5280.88      90.000    BOT
R785      2569.00     5358.00     270.000    BOT
R786      1079.49     6202.64     270.000    TOP
R787      1085.00     4890.00       0.000    TOP
R795      3591.00     6655.80      90.000    BOT
R796      3613.02     4803.68      90.000    TOP
R797      3659.61     4754.91      90.000    TOP
R801      8297.39     3408.20      90.000    BOT
R802      8150.16     3468.14     180.000    BOT
R803      7532.79     5387.18      90.000    BOT
R804      6520.46     5216.83      90.000    TOP
R805      7128.51     4765.82       0.000    TOP
R806      7200.17     4769.14     180.000    TOP
R807      8378.16     3461.14       0.000    BOT
R808      7610.05     5387.97      90.000    BOT
R809      7684.94     5402.31      90.000    BOT
R810      6520.83     5258.11     270.000    TOP
R811      8110.99     4754.79       0.000    TOP
R812      8237.28     4753.00     180.000    TOP
R813      8151.96     4283.21      90.000    BOT
R814      8268.00     4226.12     270.000    BOT
R815      6980.44     4801.89      90.000    BOT
R816      7025.91     4842.08     270.000    BOT
R817      7842.00      298.00     270.000    TOP
R819      2053.00     6423.00      90.000    BOT
R820      8379.39     3560.08     270.000    TOP
R821      2057.00     6382.00     270.000    BOT
R822      6520.83     5301.95      90.000    TOP
R824      8471.60     4039.98      90.000    TOP
R825      8386.27     3805.15       0.000    TOP
R826      8464.56     3557.57       0.000    TOP
R828      8379.13     3603.11     270.000    TOP
R829      8235.68     3710.19     270.000    TOP
R831      8507.30     3557.78     180.000    TOP
R832      8757.98     3915.33      90.000    BOT
R833      8131.81     4031.17     270.000    BOT
R834      6951.00     4550.00     270.000    BOT
R836      8477.56     3447.40      90.000    TOP
R837      8615.11     3601.63       0.000    BOT
R838      8873.66     3813.16      90.000    TOP
R839      8379.16     3519.14     270.000    TOP
R840      8349.84     3727.69       0.000    TOP
R841      8530.60     4059.98     180.000    TOP
R842      8471.60     3959.98      90.000    TOP
R843      8471.60     3999.98      90.000    TOP
R844      8488.20     4017.72       0.000    BOT
R845      7548.00     5287.00       0.000    TOP
R846      6553.78     5175.60      90.000    TOP
RST1       472.44      246.06       0.000    TOP
SKT1      1428.65     4778.00     270.000    TOP
SKT2      2398.00     4778.00     270.000    TOP
TP4       3617.92     6256.52      90.000    BOT
TP5       3691.00     5920.06     270.000    TOP
TP6       3789.65     6106.13      45.000    BOT
TP9       2028.00     5101.00       0.000    TOP
TP10      2080.00     5205.00       0.000    TOP
TP11      2171.34     5211.03       0.000    TOP
TP12      2081.00     5152.00       0.000    TOP
TP13      2576.00     5434.00       0.000    BOT
TP17      1498.24     5427.94       0.000    BOT
TP18      1601.57     5371.64       0.000    BOT
TP19      1786.00     4838.00       0.000    BOT
TP27      1847.00     5520.00       0.000    BOT
TP28      1752.00     5550.00       0.000    BOT
TP29      1705.97     5398.52       0.000    BOT
TP50      2356.14     6099.78       0.000    TOP
TP51      2069.00     5771.00     270.000    BOT
TP52      2078.20     5708.60       0.000    BOT
TP53      2218.98     6186.22      90.000    TOP
TP54      2197.00     5631.00       0.000    BOT
TP55      2379.80     5557.07       0.000    TOP
TP57      1400.90     6210.27       0.000    TOP
TP62      1639.91     6061.62       0.000    BOT
TP63      1692.42     6031.07       0.000    BOT
TP64      1549.03     6084.58       0.000    BOT
TP65      1578.00     6029.00     270.000    BOT
TP66      1690.21     6102.28     270.000    BOT
TP70      2217.00     5455.00     270.000    BOT
TP71      2357.00     5445.00       0.000    TOP
TP72      1974.00     5490.00       0.000    BOT
TP73      2205.00     5578.00       0.000    BOT
TP74      2473.00     5440.00      90.000    TOP
TP75      2381.00     5508.00       0.000    TOP
TP76      2243.00     5525.00       0.000    BOT
TP77      2411.00     5441.00       0.000    TOP
TP78      2023.80     5679.70       0.000    BOT
TP79      2232.92     5670.00       0.000    BOT
TP80      2196.88     5870.96       0.000    BOT
TP81      2196.38     5763.59       0.000    BOT
TP82      2193.75     5817.11       0.000    BOT
TP83      2132.01     5708.43      90.000    BOT
TP84      1717.80     4960.31       0.000    BOT
TP186     1658.00     6237.00       0.000    TOP
TP187     1674.00     6183.00       0.000    TOP
TP188     1619.00     6278.00       0.000    TOP
TP189     1601.00     6223.00       0.000    TOP
TP190     1868.00     5956.00       0.000    BOT
TP191     1795.00     6028.00       0.000    BOT
TP203     1848.00     4845.56       0.000    BOT
TP204     1788.00     5134.00       0.000    TOP
TP205     2360.74     5368.41      90.000    BOT
TP206     2362.60     5291.77       0.000    BOT
TP207     2381.68     5292.69       0.000    TOP
TP208     2356.58     5342.62       0.000    TOP
TP209     1972.64     5968.49       0.000    BOT
TP210     2066.36     6186.49       0.000    TOP
TP211     8359.49     4828.90       0.000    TOP
TP212     8304.26     4829.39       0.000    TOP
TP213     7410.00     5477.00       0.000    TOP
TP214     7409.00     5536.00       0.000    TOP
TP215     7242.00     3983.80       0.000    TOP
TP216     8071.00     3973.80       0.000    TOP
TP218     2190.00     6175.00       0.000    BOT
TPM1      2137.01     6799.21       0.000    TOP
U2        1877.95     5708.66     270.000    TOP
U5        2779.45     5493.94      90.000    TOP
U9        2485.31     6895.24       0.000    TOP
U10       2609.31     6893.24       0.000    TOP
U11       1428.65     4778.00      90.000    TOP
U12       3345.00     5940.00     270.000    TOP
U15       3342.52     5921.53     270.000    BOT
U16       3000.00     5982.00     270.000    BOT
U19       3028.19     5301.94      90.000    TOP
U26       3690.88     5303.81     270.000    TOP
U27       1918.00     4728.00     270.000    BOT
U28        788.76     5612.66       0.000    TOP
U29       2398.00     4778.00      90.000    TOP
U30       2776.00     5895.00     270.000    TOP
U31       2738.00     6896.00     180.000    TOP
U32       3341.39     6693.69      90.000    BOT
U33       3695.89     5110.69     270.000    TOP
U34       3668.39     5616.29     270.000    TOP
U35       4680.00      354.00      90.000    TOP
U37       2166.00     5009.80       0.000    BOT
U38       3665.35     2067.99       0.000    TOP
U45       3036.92     5791.89     270.000    BOT
U46       3727.00     4905.00     180.000    TOP
U81       8661.14     3833.99     180.000    TOP
U82       8155.88     4162.37     180.000    BOT
U83       6990.50     4672.86     180.000    BOT
U84       7182.94     4148.75       0.000    TOP
U85       8011.94     4138.75       0.000    TOP
U98       3585.00     1160.00     270.000    TOP
U99       3651.64     6126.20      90.000    TOP
U100      3650.00     5201.00     270.000    BOT
U101      3619.80     5324.00     270.000    BOT
U102      3155.12     5907.91      90.000    TOP
U103      3196.00     5129.00     270.000    BOT
U104      1373.00     5011.00     270.000    BOT
U105      3102.24     5659.63     270.000    TOP
U106      3623.00     7067.00     270.000    TOP
U107      3632.00     6852.00     270.000    TOP
USB1      3500.00      498.03       0.000    TOP
VIA1      3075.67     2793.42      90.000    TOP
VIA2      3042.67     2919.42      90.000    TOP
VIA3      3075.67     3045.42      90.000    TOP
VIA4      3042.67     3171.42      90.000    TOP
VIA5      3075.67     3297.42      90.000    TOP
VIA6      3042.67     3423.42      90.000    TOP
VIA7      3075.67     3549.42      90.000    TOP
VIA8      3042.67     3675.42      90.000    TOP
VIA9      3341.07     2856.04      90.000    TOP
VIA10     3281.82     2982.27      90.000    TOP
VIA11     3345.93     3108.34      90.000    TOP
VIA12     3281.82     3233.74      90.000    TOP
VIA13     3281.87     3485.66      90.000    TOP
VIA14     3345.82     3359.71      90.000    TOP
VIA15     3345.82     3612.24      90.000    TOP
VIA16     3281.82     3737.68      90.000    TOP
VIA25     3045.48     2667.58      90.000    TOP
VIA50     8265.00     5545.00     225.000    TOP
VIA51     8140.00     5495.00     225.000    TOP
VIA52     8080.00     5560.00     225.000    TOP
VIA53     7990.00     5555.00     225.000    TOP
VIA54     7895.00     5560.00     225.000    TOP
VIA55     7800.00     5550.00     225.000    TOP
VIA56     7695.00     5540.00     225.000    TOP
VIA57     7575.00     5495.00     225.000    TOP
VIA58     7299.19     5511.83     225.000    TOP
VIA59     7190.66     5510.93     225.000    TOP
VIA60     7099.19     5530.83     225.000    TOP
VIA61     7006.90     5523.15     225.000    TOP
VIA62     6874.35     5533.35     225.000    TOP
VIA63     6860.55     5442.49     225.000    TOP
VIA64     6722.61     5458.08     225.000    TOP
VIA65     6591.58     5402.37     225.000    TOP
VIA66     8411.32     5479.97      45.000    TOP
VIA67     7222.86     5235.19     180.000    TOP
X1        3646.61     6488.49     180.000    TOP
X2        2751.33     6152.67     180.000    TOP

EOS

#From(Function(Sicard.Report) Version 3.0)